G04 ================== begin FILE IDENTIFICATION RECORD ==================*
G04 Layout Name:  14545-sa.brd*
G04 Film Name:    L7GND*
G04 File Format:  Gerber RS274X*
G04 File Origin:  Cadence Allegro 16.5-S056*
G04 Origin Date:  Fri Aug 01 17:58:55 2014*
G04 *
G04 Layer:  VIA CLASS/L7GND*
G04 Layer:  PIN/L7GND*
G04 Layer:  ETCH/L7GND*
G04 Layer:  DRAWING FORMAT/LAYER_PCB_STORY*
G04 Layer:  DRAWING FORMAT/LAYER_L7GND*
G04 *
G04 Offset:    (0.00 0.00)*
G04 Mirror:    No*
G04 Mode:      Negative*
G04 Rotation:  0*
G04 FullContactRelief:  No*
G04 UndefLineWidth:     6.00*
G04 ================== end FILE IDENTIFICATION RECORD ====================*
%FSLAX35Y35*MOIN*%
%IR0*IPPOS*OFA0.00000B0.00000*MIA0B0*SFA1.00000B1.00000*%
%AMMACRO19*
4,1,16,.07873,.05044,
.086293,.036002,
.091233,.020471,
.093402,.004317,
.092733,-.011967,
.089246,-.027888,
.083047,-.042962,
.07873,-.05044,
.08234,-.05406,
.090476,-.038941,
.095864,-.022638,
.098339,-.005647,
.097825,.011515,
.094339,.028327,
.087987,.044279,
.08234,.05406,
.07873,.05044,
0.0*
4,1,16,.05044,-.07873,
.036002,-.086293,
.020471,-.091233,
.004317,-.093402,
-.011967,-.092733,
-.027888,-.089246,
-.042962,-.083047,
-.05044,-.07873,
-.05406,-.08234,
-.038941,-.090476,
-.022638,-.095864,
-.005647,-.098339,
.011515,-.097825,
.028327,-.094339,
.044279,-.087987,
.05406,-.08234,
.05044,-.07873,
0.0*
4,1,16,-.07873,-.05044,
-.086293,-.036002,
-.091233,-.020471,
-.093402,-.004317,
-.092733,.011967,
-.089246,.027888,
-.083047,.042962,
-.07873,.05044,
-.08234,.05406,
-.090476,.038941,
-.095864,.022638,
-.098339,.005647,
-.097825,-.011515,
-.094339,-.028327,
-.087987,-.044279,
-.08234,-.05406,
-.07873,-.05044,
0.0*
4,1,16,-.05044,.07873,
-.036002,.086293,
-.020471,.091233,
-.004317,.093402,
.011967,.092733,
.027888,.089246,
.042962,.083047,
.05044,.07873,
.05406,.08234,
.038941,.090476,
.022638,.095864,
.005647,.098339,
-.011515,.097825,
-.028327,.094339,
-.044279,.087987,
-.05406,.08234,
-.05044,.07873,
0.0*
%
%ADD19MACRO19*%
%ADD15C,.032*%
%AMMACRO20*
4,1,20,-.01,-.05608,
-.015853,-.053819,
-.021224,-.050576,
-.025951,-.046449,
-.029889,-.041565,
-.032919,-.03607,
-.034949,-.030133,
-.035918,-.023934,
-.036,-.0215,
-.036,-.015,
-.031,-.015,
-.031,-.0215,
-.030529,-.026882,
-.029131,-.032101,
-.026847,-.036998,
-.023748,-.041424,
-.019928,-.045244,
-.015502,-.048343,
-.010605,-.050627,
-.01,-.05084,
-.01,-.05608,
90.*
4,1,20,.01,-.05608,
.01,-.05084,
.014943,-.048658,
.019432,-.045652,
.023331,-.041911,
.026521,-.03755,
.028905,-.032702,
.030411,-.027513,
.030993,-.022142,
.031,-.0215,
.031,-.015,
.036,-.015,
.036,-.0215,
.035453,-.027751,
.033829,-.033811,
.031177,-.039498,
.027579,-.044638,
.023142,-.049074,
.018002,-.052673,
.012316,-.055325,
.01,-.05608,
90.*
4,1,20,-.036,.015,
-.036,.0215,
-.035453,.027751,
-.033829,.033811,
-.031177,.039498,
-.027579,.044638,
-.023142,.049074,
-.018002,.052673,
-.012316,.055325,
-.01,.05608,
-.01,.05084,
-.014943,.048658,
-.019432,.045652,
-.023331,.041911,
-.026521,.03755,
-.028905,.032702,
-.030411,.027513,
-.030993,.022142,
-.031,.0215,
-.031,.015,
-.036,.015,
90.*
4,1,20,.031,.015,
.031,.0215,
.030529,.026882,
.029131,.032101,
.026847,.036998,
.023748,.041424,
.019928,.045244,
.015502,.048343,
.010605,.050627,
.01,.05084,
.01,.05608,
.015853,.053819,
.021224,.050576,
.025951,.046449,
.029889,.041565,
.032919,.03607,
.034949,.030133,
.035918,.023934,
.036,.0215,
.036,.015,
.031,.015,
90.*
%
%ADD20MACRO20*%
%ADD14C,.036*%
%AMMACRO22*
4,1,15,.00398,.00044,
.003999,.000208,
.004004,-.000025,
.003996,-.000258,
.00398,-.00044,
.00483,-.00129,
.004897,-.001007,
.004947,-.000721,
.004981,-.000432,
.004997,-.000141,
.004997,.000149,
.00498,.00044,
.004946,.000729,
.004895,.001015,
.00483,.00129,
.00398,.00044,
90.*
4,1,15,.00044,-.00398,
.000208,-.003999,
-.000025,-.004004,
-.000258,-.003996,
-.00044,-.00398,
-.00129,-.00483,
-.001007,-.004897,
-.000721,-.004947,
-.000432,-.004981,
-.000141,-.004997,
.000149,-.004997,
.00044,-.00498,
.000729,-.004946,
.001015,-.004895,
.00129,-.00483,
.00044,-.00398,
90.*
4,1,15,-.00398,-.00044,
-.003999,-.000208,
-.004004,.000025,
-.003996,.000258,
-.00398,.00044,
-.00483,.00129,
-.004897,.001007,
-.004947,.000721,
-.004981,.000432,
-.004997,.000141,
-.004997,-.000149,
-.00498,-.00044,
-.004946,-.000729,
-.004895,-.001015,
-.00483,-.00129,
-.00398,-.00044,
90.*
4,1,15,-.00044,.00398,
-.000208,.003999,
.000025,.004004,
.000258,.003996,
.00044,.00398,
.00129,.00483,
.001007,.004897,
.000721,.004947,
.000432,.004981,
.000141,.004997,
-.000149,.004997,
-.00044,.00498,
-.000729,.004946,
-.001015,.004895,
-.00129,.00483,
-.00044,.00398,
90.*
%
%ADD22MACRO22*%
%AMMACRO13*
4,1,15,.00398,.00044,
.003999,.000208,
.004004,-.000025,
.003996,-.000258,
.00398,-.00044,
.00483,-.00129,
.004897,-.001007,
.004947,-.000721,
.004981,-.000432,
.004997,-.000141,
.004997,.000149,
.00498,.00044,
.004946,.000729,
.004895,.001015,
.00483,.00129,
.00398,.00044,
0.0*
4,1,15,.00044,-.00398,
.000208,-.003999,
-.000025,-.004004,
-.000258,-.003996,
-.00044,-.00398,
-.00129,-.00483,
-.001007,-.004897,
-.000721,-.004947,
-.000432,-.004981,
-.000141,-.004997,
.000149,-.004997,
.00044,-.00498,
.000729,-.004946,
.001015,-.004895,
.00129,-.00483,
.00044,-.00398,
0.0*
4,1,15,-.00398,-.00044,
-.003999,-.000208,
-.004004,.000025,
-.003996,.000258,
-.00398,.00044,
-.00483,.00129,
-.004897,.001007,
-.004947,.000721,
-.004981,.000432,
-.004997,.000141,
-.004997,-.000149,
-.00498,-.00044,
-.004946,-.000729,
-.004895,-.001015,
-.00483,-.00129,
-.00398,-.00044,
0.0*
4,1,15,-.00044,.00398,
-.000208,.003999,
.000025,.004004,
.000258,.003996,
.00044,.00398,
.00129,.00483,
.001007,.004897,
.000721,.004947,
.000432,.004981,
.000141,.004997,
-.000149,.004997,
-.00044,.00498,
-.000729,.004946,
-.001015,.004895,
-.00129,.00483,
-.00044,.00398,
0.0*
%
%ADD13MACRO13*%
%ADD18C,.101*%
%ADD10C,.114*%
%AMMACRO17*
4,1,20,-.01,-.05608,
-.015853,-.053819,
-.021224,-.050576,
-.025951,-.046449,
-.029889,-.041565,
-.032919,-.03607,
-.034949,-.030133,
-.035918,-.023934,
-.036,-.0215,
-.036,-.015,
-.031,-.015,
-.031,-.0215,
-.030529,-.026882,
-.029131,-.032101,
-.026847,-.036998,
-.023748,-.041424,
-.019928,-.045244,
-.015502,-.048343,
-.010605,-.050627,
-.01,-.05084,
-.01,-.05608,
270.*
4,1,20,.01,-.05608,
.01,-.05084,
.014943,-.048658,
.019432,-.045652,
.023331,-.041911,
.026521,-.03755,
.028905,-.032702,
.030411,-.027513,
.030993,-.022142,
.031,-.0215,
.031,-.015,
.036,-.015,
.036,-.0215,
.035453,-.027751,
.033829,-.033811,
.031177,-.039498,
.027579,-.044638,
.023142,-.049074,
.018002,-.052673,
.012316,-.055325,
.01,-.05608,
270.*
4,1,20,-.036,.015,
-.036,.0215,
-.035453,.027751,
-.033829,.033811,
-.031177,.039498,
-.027579,.044638,
-.023142,.049074,
-.018002,.052673,
-.012316,.055325,
-.01,.05608,
-.01,.05084,
-.014943,.048658,
-.019432,.045652,
-.023331,.041911,
-.026521,.03755,
-.028905,.032702,
-.030411,.027513,
-.030993,.022142,
-.031,.0215,
-.031,.015,
-.036,.015,
270.*
4,1,20,.031,.015,
.031,.0215,
.030529,.026882,
.029131,.032101,
.026847,.036998,
.023748,.041424,
.019928,.045244,
.015502,.048343,
.010605,.050627,
.01,.05084,
.01,.05608,
.015853,.053819,
.021224,.050576,
.025951,.046449,
.029889,.041565,
.032919,.03607,
.034949,.030133,
.035918,.023934,
.036,.0215,
.036,.015,
.031,.015,
270.*
%
%ADD17MACRO17*%
%ADD12C,.119*%
%ADD23C,.174*%
%AMMACRO21*
4,1,15,.00398,.00044,
.003999,.000208,
.004004,-.000025,
.003996,-.000258,
.00398,-.00044,
.00483,-.00129,
.004897,-.001007,
.004947,-.000721,
.004981,-.000432,
.004997,-.000141,
.004997,.000149,
.00498,.00044,
.004946,.000729,
.004895,.001015,
.00483,.00129,
.00398,.00044,
180.*
4,1,15,.00044,-.00398,
.000208,-.003999,
-.000025,-.004004,
-.000258,-.003996,
-.00044,-.00398,
-.00129,-.00483,
-.001007,-.004897,
-.000721,-.004947,
-.000432,-.004981,
-.000141,-.004997,
.000149,-.004997,
.00044,-.00498,
.000729,-.004946,
.001015,-.004895,
.00129,-.00483,
.00044,-.00398,
180.*
4,1,15,-.00398,-.00044,
-.003999,-.000208,
-.004004,.000025,
-.003996,.000258,
-.00398,.00044,
-.00483,.00129,
-.004897,.001007,
-.004947,.000721,
-.004981,.000432,
-.004997,.000141,
-.004997,-.000149,
-.00498,-.00044,
-.004946,-.000729,
-.004895,-.001015,
-.00483,-.00129,
-.00398,-.00044,
180.*
4,1,15,-.00044,.00398,
-.000208,.003999,
.000025,.004004,
.000258,.003996,
.00044,.00398,
.00129,.00483,
.001007,.004897,
.000721,.004947,
.000432,.004981,
.000141,.004997,
-.000149,.004997,
-.00044,.00498,
-.000729,.004946,
-.001015,.004895,
-.00129,.00483,
-.00044,.00398,
180.*
%
%ADD21MACRO21*%
%AMMACRO11*
4,1,15,.00398,.00044,
.003999,.000208,
.004004,-.000025,
.003996,-.000258,
.00398,-.00044,
.00483,-.00129,
.004897,-.001007,
.004947,-.000721,
.004981,-.000432,
.004997,-.000141,
.004997,.000149,
.00498,.00044,
.004946,.000729,
.004895,.001015,
.00483,.00129,
.00398,.00044,
270.*
4,1,15,.00044,-.00398,
.000208,-.003999,
-.000025,-.004004,
-.000258,-.003996,
-.00044,-.00398,
-.00129,-.00483,
-.001007,-.004897,
-.000721,-.004947,
-.000432,-.004981,
-.000141,-.004997,
.000149,-.004997,
.00044,-.00498,
.000729,-.004946,
.001015,-.004895,
.00129,-.00483,
.00044,-.00398,
270.*
4,1,15,-.00398,-.00044,
-.003999,-.000208,
-.004004,.000025,
-.003996,.000258,
-.00398,.00044,
-.00483,.00129,
-.004897,.001007,
-.004947,.000721,
-.004981,.000432,
-.004997,.000141,
-.004997,-.000149,
-.00498,-.00044,
-.004946,-.000729,
-.004895,-.001015,
-.00483,-.00129,
-.00398,-.00044,
270.*
4,1,15,-.00044,.00398,
-.000208,.003999,
.000025,.004004,
.000258,.003996,
.00044,.00398,
.00129,.00483,
.001007,.004897,
.000721,.004947,
.000432,.004981,
.000141,.004997,
-.000149,.004997,
-.00044,.00498,
-.000729,.004946,
-.001015,.004895,
-.00129,.00483,
-.00044,.00398,
270.*
%
%ADD11MACRO11*%
%AMMACRO16*
4,1,16,.07256,.04427,
.079145,.030998,
.083325,.016783,
.084974,.002059,
.08404,-.012728,
.080553,-.027128,
.074619,-.040704,
.07256,-.04427,
.07619,-.04791,
.083352,-.033952,
.087981,-.018962,
.089937,-.003396,
.089161,.012273,
.085675,.027569,
.079586,.042027,
.07619,.04791,
.07256,.04427,
0.0*
4,1,16,.04427,-.07256,
.030998,-.079145,
.016783,-.083325,
.002059,-.084974,
-.012728,-.08404,
-.027128,-.080553,
-.040704,-.074619,
-.04427,-.07256,
-.04791,-.07619,
-.033952,-.083352,
-.018962,-.087981,
-.003396,-.089937,
.012273,-.089161,
.027569,-.085675,
.042027,-.079586,
.04791,-.07619,
.04427,-.07256,
0.0*
4,1,16,-.07256,-.04427,
-.079145,-.030998,
-.083325,-.016783,
-.084974,-.002059,
-.08404,.012728,
-.080553,.027128,
-.074619,.040704,
-.07256,.04427,
-.07619,.04791,
-.083352,.033952,
-.087981,.018962,
-.089937,.003396,
-.089161,-.012273,
-.085675,-.027569,
-.079586,-.042027,
-.07619,-.04791,
-.07256,-.04427,
0.0*
4,1,16,-.04427,.07256,
-.030998,.079145,
-.016783,.083325,
-.002059,.084974,
.012728,.08404,
.027128,.080553,
.040704,.074619,
.04427,.07256,
.04791,.07619,
.033952,.083352,
.018962,.087981,
.003396,.089937,
-.012273,.089161,
-.027569,.085675,
-.042027,.079586,
-.04791,.07619,
-.04427,.07256,
0.0*
%
%ADD16MACRO16*%
%ADD24C,.02*%
%ADD25C,.006*%
%ADD32R,.142X.028*%
%ADD30C,.09704*%
%ADD29C,.11504*%
%ADD26O,.0802X.0462*%
%ADD31C,.17004*%
%ADD28O,.0812X.0462*%
%ADD27O,.0822X.0462*%
G75*
%LPD*%
G75*
G36*
G01X-6000Y-6000D02*
X1039465D01*
Y1998126D01*
X-6000D01*
Y-6000D01*
G37*
%LPC*%
G75*
G36*
G01X24206Y426804D02*
X24081Y423407D01*
X24083D01*
X24092Y423216D01*
G03X24111Y423005I2307J101D01*
G02X23797Y422814I-198J-28D01*
G03X19883Y424067I-3915J-5491D01*
G01X3213D01*
X3004Y424276D01*
Y819818D01*
X3213Y820027D01*
X19882D01*
G03Y833516I0J6745D01*
G01X3213D01*
X3004Y833725D01*
Y1194621D01*
X3214Y1194831D01*
X19882D01*
G03Y1208319I0J6744D01*
G01X3213D01*
X3004Y1208528D01*
Y1394621D01*
X3214Y1394831D01*
X5468D01*
Y1394268D01*
X19668D01*
Y1394831D01*
X19882D01*
G03Y1408319I0J6744D01*
G01X3213D01*
X3004Y1408528D01*
Y1804070D01*
X3213Y1804279D01*
X19882D01*
G03Y1817768I0J6744D01*
G01X3213D01*
X3004Y1817977D01*
Y1988189D01*
G02X3937Y1989122I933J0D01*
G01X1029528D01*
G02X1030461Y1988189I0J-933D01*
G01Y1686599D01*
X1028283Y1684421D01*
X1024211D01*
G03X1016287Y1676496I1J-7925D01*
G01Y1621265D01*
X1014109Y1619087D01*
X989744D01*
G03Y1608866I0J-5110D01*
G01X1014109D01*
X1016287Y1606688D01*
Y1433740D01*
G03X1024211Y1425815I7925J0D01*
G01X1028283D01*
X1030461Y1423637D01*
Y3937D01*
G02X1029528Y3004I-933J0D01*
G01X3937D01*
G02X3004Y3937I0J933D01*
G01Y210369D01*
X3214Y210579D01*
X19882D01*
G03Y224067I0J6744D01*
G01X3213D01*
X3004Y224276D01*
Y410369D01*
X3214Y410579D01*
X5468D01*
Y410016D01*
X19668D01*
Y410579D01*
X19882D01*
G03X25866Y420434I0J6744D01*
G02X26247Y421018I355J185D01*
G03X28694Y423060I152J2304D01*
G01X28714Y423237D01*
X28717D01*
X28842Y426635D01*
X28840D01*
X28831Y426826D01*
G03X24221Y426887I-2307J-106D01*
G01X24215Y426813D01*
X24206Y426804D01*
G37*
%LPD*%
G75*
G36*
G01X853512Y1873346D02*
G02X853485Y1868726I-14J-2310D01*
G01X850085Y1868746D01*
G02X850113Y1873366I14J2310D01*
G01X853512Y1873346D01*
G37*
G36*
G01X121083Y1870817D02*
X121080Y1870995D01*
X121077D01*
X121276Y1874390D01*
X121278D01*
X121305Y1874580D01*
G02X125902Y1874296I2287J-325D01*
G01X125905Y1874118D01*
X125908D01*
X125709Y1870724D01*
X125700Y1870715D01*
X125693Y1870643D01*
G02X121083Y1870817I-2300J216D01*
G37*
G36*
G01X869224Y1861839D02*
G02X864604Y1861840I-2310J1D01*
G01Y1865615D01*
G02X869224I2310J0D01*
G01Y1861839D01*
G37*
G36*
G01X140309Y1861496D02*
G02X135689Y1861497I-2310J1D01*
G01Y1865151D01*
G02X140309I2310J0D01*
G01Y1861496D01*
G37*
G36*
G01X82886Y1748948D02*
X83033Y1752344D01*
G02X87649Y1752145I2308J-99D01*
G01X87502Y1748748D01*
G02X82886Y1748948I-2308J100D01*
G37*
G36*
G01X107093Y1739419D02*
X107082Y1739608D01*
X107080D01*
X107180Y1743607D01*
X107189Y1743616D01*
X107194Y1743692D01*
G02X111805Y1743681I2305J-143D01*
G01X111816Y1743492D01*
X111818D01*
X111718Y1739492D01*
X111715D01*
X111696Y1739313D01*
G02X107093Y1739419I-2297J238D01*
G37*
G36*
G01X48187Y1724823D02*
G02X43567I-2310J0D01*
G01Y1728478D01*
G02X48187Y1728477I2310J-1D01*
G01Y1724823D01*
G37*
G36*
G01X29660Y1642692D02*
G02X29593Y1647312I-34J2310D01*
G01X32993Y1647361D01*
G02X33059Y1642741I33J-2310D01*
G01X29660Y1642692D01*
G37*
G36*
G01X30219Y1509592D02*
G02X30012Y1514208I-104J2308D01*
G01X33409Y1514359D01*
G02X33615Y1509743I103J-2308D01*
G01X30219Y1509592D01*
G37*
G36*
G01X852326Y1468656D02*
G02X852250Y1464036I-38J-2310D01*
G01X848851Y1464092D01*
G02X848926Y1468712I38J2310D01*
G01X852326Y1468656D01*
G37*
G36*
G01X30485Y1460210D02*
G02X30272Y1464826I-106J2308D01*
G01X33809Y1464989D01*
G02X34021Y1460373I106J-2308D01*
G01X30485Y1460210D01*
G37*
G36*
G01X875767Y1456129D02*
X875740Y1456319D01*
X875738D01*
X875537Y1459860D01*
X875540D01*
X875544Y1460038D01*
G02X880159Y1460121I2309J-48D01*
G01X880170Y1459922D01*
X880180D01*
X880370Y1456582D01*
X880362Y1456574D01*
X880363Y1456489D01*
G02X875767Y1456129I-2309J-39D01*
G37*
G36*
G01X140702Y1456131D02*
X140683Y1456310D01*
X140680D01*
X140581Y1459937D01*
X140583D01*
X140594Y1460126D01*
G02X145197Y1460242I2306J-127D01*
G01X145216Y1460063D01*
X145219D01*
X145318Y1456437D01*
X145310Y1456429D01*
X145309Y1456347D01*
G02X140702Y1456131I-2310J26D01*
G37*
G36*
G01X107245Y1440601D02*
G02X102625Y1440668I-2310J33D01*
G01X102689Y1444975D01*
G02X107309Y1444907I2310J-34D01*
G01X107245Y1440601D01*
G37*
G36*
G01X31903Y1430445D02*
X31745Y1430553D01*
X31744Y1430551D01*
X29037Y1432749D01*
X29039Y1432752D01*
X28910Y1432874D01*
G02X31955Y1436343I1590J1676D01*
G01X32110Y1436217D01*
X32116Y1436225D01*
X34668Y1434154D01*
Y1434142D01*
X34736Y1434083D01*
G02X31903Y1430445I-1529J-1732D01*
G37*
G36*
G01X119700Y1426200D02*
G02X115080Y1426201I-2310J1D01*
G01Y1429976D01*
G02X119700I2310J0D01*
G01Y1426200D01*
G37*
G36*
G01X31582Y1387198D02*
X31409Y1387257D01*
X31408Y1387255D01*
X27575Y1388922D01*
X27555Y1388942D01*
X27523Y1388957D01*
G02X29250Y1393235I977J2093D01*
G01X29423Y1393176D01*
X29424Y1393178D01*
X33258Y1391511D01*
X33257Y1391509D01*
X33421Y1391421D01*
G02X31582Y1387198I-1089J-2038D01*
G37*
G36*
G01X99536Y1373462D02*
G02X94922Y1373213I-2307J-125D01*
G01X94693Y1377476D01*
G02X99307Y1377724I2307J124D01*
G01X99536Y1373462D01*
G37*
G36*
G01X114719Y1357817D02*
G02X110161Y1358576I-2279J380D01*
G01X110720Y1361930D01*
G02X115278Y1361170I2279J-380D01*
G01X114719Y1357817D01*
G37*
G36*
G01X115810Y1344499D02*
G02X111190Y1344500I-2310J1D01*
G01Y1348154D01*
G02X115810I2310J0D01*
G01Y1344499D01*
G37*
G36*
G01X104660D02*
G02X100040Y1344500I-2310J1D01*
G01Y1348154D01*
G02X104660I2310J0D01*
G01Y1344499D01*
G37*
G36*
G01X111538Y1333315D02*
G02X106918I-2310J0D01*
G01Y1337091D01*
G02X111538Y1337090I2310J-1D01*
G01Y1333315D01*
G37*
G36*
G01X139791Y1077561D02*
G02X135171Y1077554I-2310J-3D01*
G01X135167Y1081174D01*
G02X139787Y1081180I2310J3D01*
G01Y1081174D01*
X139791Y1077561D01*
G37*
G36*
G01X126733Y1077522D02*
G02X122113Y1077523I-2310J1D01*
G01Y1081177D01*
G02X126733I2310J0D01*
G01Y1077522D01*
G37*
G36*
G01X850865Y1063751D02*
G02X850800Y1059131I-32J-2310D01*
G01X847200Y1059182D01*
G02X847266Y1063802I33J2310D01*
G01X850865Y1063751D01*
G37*
G36*
G01X880536Y1051279D02*
G02X875930Y1050912I-2303J-183D01*
G01X875661Y1054302D01*
G02X880267Y1054668I2303J183D01*
G01X880536Y1051279D01*
G37*
G36*
G01X126309Y1050650D02*
G02X121689I-2310J0D01*
G01Y1054051D01*
G02X126309Y1054050I2310J-1D01*
G01Y1050650D01*
G37*
G36*
G01X88693Y937322D02*
G02X84105Y936778I-2294J-272D01*
G01X83705Y940156D01*
G02X88293Y940701I2294J272D01*
G01X88693Y937322D01*
G37*
G36*
G01X111403Y928423D02*
G02X106795Y928078I-2304J-173D01*
G01X106541Y931485D01*
G02X111149Y931829I2304J172D01*
G01X111403Y928423D01*
G37*
G36*
G01X29997Y667446D02*
G02X25377Y667447I-2310J1D01*
G01Y671101D01*
G02X29997I2310J0D01*
G01Y667446D01*
G37*
G36*
G01X847814Y653060D02*
G02X847730Y657680I-42J2310D01*
G01X851129Y657742D01*
G02X851214Y653122I42J-2310D01*
G01X847814Y653060D01*
G37*
G36*
G01X880906Y645572D02*
G02X876286Y645573I-2310J1D01*
G01Y649348D01*
G02X880906I2310J0D01*
G01Y645572D01*
G37*
G36*
G01X146548Y645355D02*
G02X141928Y645356I-2310J1D01*
G01Y649131D01*
G02X146548I2310J0D01*
G01Y645355D01*
G37*
G36*
G01X132021Y646825D02*
G02X130779Y642375I-621J-2225D01*
G01X127409Y643317D01*
X127408D01*
G02X128620Y647775I591J2233D01*
G01X132021Y646825D01*
G37*
G36*
G01X127809Y635549D02*
G02X123189Y635550I-2310J1D01*
G01Y638950D01*
G02X127809I2310J0D01*
G01Y635549D01*
G37*
G36*
G01X57689Y537547D02*
G02X62309Y537553I2310J3D01*
G01Y537547D01*
X62313Y534154D01*
G02X57693Y534147I-2310J-3D01*
G01X57689Y537547D01*
G37*
G36*
G01X88509Y532249D02*
G02X83889Y532250I-2310J1D01*
G01Y536025D01*
G02X88509I2310J0D01*
G01Y532249D01*
G37*
G36*
G01X28909Y525647D02*
G02X24289Y525648I-2310J1D01*
G01Y529302D01*
G02X28909I2310J0D01*
G01Y525647D01*
G37*
G36*
G01X38809Y517774D02*
G02X34189Y517775I-2310J1D01*
G01Y521550D01*
G02X38809I2310J0D01*
G01Y517774D01*
G37*
G36*
G01X28709Y501965D02*
G02X24089Y501966I-2310J1D01*
G01Y505741D01*
G02X28709I2310J0D01*
G01Y501965D01*
G37*
G36*
G01X62291Y486368D02*
X62391Y489768D01*
G02X67009Y489632I2309J-68D01*
G01X66909Y486244D01*
G02X62291Y486368I-2309J56D01*
G37*
G36*
G01X23990Y478372D02*
X23987Y478551D01*
X23984D01*
X24200Y481945D01*
X24202D01*
X24230Y482134D01*
G02X28824Y481830I2285J-337D01*
G01X28827Y481651D01*
X28830D01*
X28614Y478258D01*
X28604Y478248D01*
X28597Y478177D01*
G02X23990Y478372I-2298J227D01*
G37*
G36*
G01X62087Y474442D02*
G02X66707Y474450I2310J4D01*
G01Y474442D01*
X66713Y471051D01*
G02X62093Y471042I-2310J-5D01*
G01X62087Y474442D01*
G37*
G36*
G01X25191Y460155D02*
G03X25145Y460767I-279J287D01*
G02X24176Y462656I1341J1881D01*
G01X24189Y466258D01*
G02X28809Y466242I2310J-8D01*
G01X28796Y462641D01*
G02X28094Y460990I-2310J7D01*
G03X28140Y460378I279J-287D01*
G02X29096Y458740I-1341J-1881D01*
G01X29115Y458561D01*
X29118D01*
X29218Y454915D01*
X29210Y454907D01*
X29209Y454825D01*
G02X24602Y454607I-2310J24D01*
G01X24583Y454786D01*
X24580D01*
X24480Y458433D01*
X24482D01*
X24493Y458622D01*
G02X25191Y460155I2306J-125D01*
G37*
G36*
G01X28801Y439278D02*
G02X24183Y439423I-2309J73D01*
G01X24290Y442822D01*
G02X28908Y442676I2309J-73D01*
G01X28801Y439278D01*
G37*
G36*
G01X28609Y399600D02*
G02X23989Y399601I-2310J1D01*
G01Y403376D01*
G02X28609I2310J0D01*
G01Y399600D01*
G37*
G36*
G01Y383853D02*
G02X23989Y383854I-2310J1D01*
G01Y387629D01*
G02X28609I2310J0D01*
G01Y383853D01*
G37*
G36*
G01X851323Y252284D02*
G02X851233Y247664I-45J-2310D01*
G01X847834Y247730D01*
G02X847923Y252350I44J2310D01*
G01X851323Y252284D01*
G37*
G36*
G01X120532Y248709D02*
X120497Y248888D01*
X120494D01*
X120092Y252425D01*
X120100Y252433D01*
X120093Y252524D01*
G02X124664Y253129I2304J163D01*
G01X124699Y252950D01*
X124702D01*
X125104Y249412D01*
X125102D01*
X125108Y249225D01*
G02X120532Y248709I-2309J-75D01*
G37*
G36*
G01X880388Y240102D02*
G02X875768Y240103I-2310J1D01*
G01Y243878D01*
G02X880388I2310J0D01*
G01Y240102D01*
G37*
G36*
G01X152309Y239728D02*
G02X147689Y239729I-2310J1D01*
G01Y243504D01*
G02X152309I2310J0D01*
G01Y239728D01*
G37*
G36*
G01X88902Y126569D02*
G02X84296Y126931I-2303J181D01*
G01X84596Y130747D01*
G02X89202Y130386I2303J-181D01*
G01X88902Y126569D01*
G37*
G36*
G01X29831Y1671683D02*
X29868Y1671670D01*
X31469Y1671768D01*
X31504Y1671784D01*
G02X31763Y1667523I990J-2078D01*
G01X31726Y1667536D01*
X30125Y1667438D01*
X30090Y1667422D01*
G02X29831Y1671683I-990J2078D01*
G37*
G36*
G01X29128Y1663280D02*
X29153Y1663274D01*
X31331Y1663330D01*
X31356Y1663337D01*
G02X31471Y1658886I643J-2210D01*
G01X31446Y1658892D01*
X29268Y1658836D01*
X29243Y1658829D01*
G02X29128Y1663280I-643J2210D01*
G37*
G36*
G01X30984Y1626606D02*
X28932Y1627819D01*
X28906Y1627826D01*
G02X31159Y1631645I593J2224D01*
G01X31178Y1631625D01*
X33232Y1630412D01*
X33259Y1630405D01*
G02X31003Y1626586I-596J-2224D01*
G01X30984Y1626606D01*
G37*
G36*
G01X31654Y1611314D02*
X29544D01*
X29518Y1611307D01*
G02Y1615741I-619J2217D01*
G01X29544Y1615734D01*
X31654D01*
X31680Y1615741D01*
G02Y1611307I619J-2217D01*
G01X31654Y1611314D01*
G37*
G36*
G01X30330Y1569755D02*
X27102Y1569903D01*
X27099D01*
G02X27310Y1574499I23J2302D01*
G01X27313D01*
X30540Y1574351D01*
X30543D01*
G02X30333Y1569755I-22J-2302D01*
G01X30330D01*
G37*
G36*
G01X29782Y1518465D02*
X29789Y1518491D01*
Y1520855D01*
X29782Y1520881D01*
G02X34216I2217J619D01*
G01X34209Y1520855D01*
Y1518491D01*
X34216Y1518465D01*
G02X29782I-2217J-619D01*
G37*
G36*
G01X33348Y1479670D02*
X31669Y1479847D01*
X31632Y1479837D01*
G02X32081Y1484082I-633J2213D01*
G01X32116Y1484063D01*
X33794Y1483886D01*
X33832Y1483896D01*
G02X33383Y1479651I633J-2213D01*
G01X33348Y1479670D01*
G37*
G36*
G01X126312Y1468141D02*
X126293Y1468106D01*
X126017Y1465700D01*
X126027Y1465663D01*
G02X121786Y1466151I-2219J-613D01*
G01X121805Y1466185D01*
X122081Y1468591D01*
X122071Y1468628D01*
G02X126312Y1468141I2219J613D01*
G37*
G36*
G01X29485Y1450459D02*
X29523Y1450445D01*
X31080Y1450515D01*
X31116Y1450532D01*
G02X31306Y1446285I978J-2084D01*
G01X31268Y1446299D01*
X29711Y1446229D01*
X29675Y1446212D01*
G02X29485Y1450459I-978J2084D01*
G37*
G36*
G01X29054Y1413851D02*
Y1413859D01*
X32505Y1413777D01*
X32512Y1413770D01*
X32587Y1413766D01*
G02X32396Y1409167I-136J-2298D01*
G01Y1409159D01*
X28944Y1409241D01*
Y1409242D01*
X28764Y1409260D01*
G02X29054Y1413851I236J2290D01*
G37*
G36*
G01X27808Y1371991D02*
Y1371987D01*
X27857Y1368569D01*
Y1368566D01*
G02X23257Y1368501I-2299J-120D01*
G01Y1368505D01*
X23208Y1371922D01*
Y1371926D01*
G02X27808Y1371991I2299J120D01*
G37*
G36*
G01X89190Y1346539D02*
Y1342952D01*
G02X84590I-2300J-92D01*
G01Y1346543D01*
G02X89190I2300J92D01*
G01Y1346539D01*
G37*
G36*
G01X52602Y699187D02*
Y699183D01*
X52706Y695966D01*
Y695962D01*
G02X48108Y695814I-2296J-161D01*
G01Y695818D01*
X48004Y699034D01*
Y699038D01*
G02X52602Y699187I2296J163D01*
G37*
G36*
G01X24435Y651912D02*
X24432Y652089D01*
X24431D01*
X24693Y656685D01*
X24720Y656872D01*
G02X29301Y656595I2279J-322D01*
G01X29304Y656418D01*
X29305D01*
X29043Y651826D01*
X29042D01*
X29019Y651652D01*
G02X24435Y651912I-2282J305D01*
G37*
G36*
G01X28868Y639508D02*
Y636042D01*
G02X24268I-2300J-92D01*
G01Y639512D01*
G02X28868I2300J92D01*
G01Y639508D01*
G37*
G36*
G01X29799Y623761D02*
Y620295D01*
G02X25199I-2300J-92D01*
G01Y623765D01*
G02X29799I2300J92D01*
G01Y623761D01*
G37*
G36*
G01X117986Y129129D02*
Y126894D01*
X118001Y126857D01*
G02X113751I-2125J-884D01*
G01X113766Y126894D01*
Y129129D01*
X113751Y129166D01*
G02X118001I2125J884D01*
G01X117986Y129129D01*
G37*
G54D32*
X12568Y375983D03*
Y379920D03*
Y391731D03*
Y395668D03*
Y407479D03*
Y431103D03*
Y435040D03*
Y446851D03*
Y450788D03*
Y462599D03*
Y466536D03*
Y478347D03*
Y482284D03*
Y494095D03*
Y498032D03*
Y509843D03*
Y513780D03*
Y525591D03*
Y529528D03*
Y580709D03*
Y584646D03*
Y612205D03*
Y616142D03*
Y627953D03*
Y631890D03*
Y643701D03*
Y647638D03*
Y659449D03*
Y663386D03*
Y675197D03*
Y679134D03*
Y1360235D03*
Y1364172D03*
Y1375983D03*
Y1379920D03*
Y1391731D03*
Y1415355D03*
Y1419292D03*
Y1431103D03*
Y1435040D03*
Y1446851D03*
Y1450788D03*
Y1462599D03*
Y1466536D03*
Y1478347D03*
Y1482284D03*
Y1494095D03*
Y1498032D03*
Y1509843D03*
Y1513780D03*
Y1564961D03*
Y1568898D03*
Y1596457D03*
Y1600394D03*
Y1612205D03*
Y1616142D03*
Y1627953D03*
Y1631890D03*
Y1643701D03*
Y1647638D03*
Y1659449D03*
Y1663386D03*
G54D30*
X78150Y28858D03*
Y178464D03*
Y434370D03*
Y583976D03*
Y839882D03*
Y989488D03*
Y1245394D03*
Y1395000D03*
Y1650906D03*
Y1800512D03*
X158071Y191614D03*
Y341220D03*
Y597126D03*
Y746732D03*
Y1002638D03*
Y1152244D03*
Y1408150D03*
Y1557756D03*
Y1813662D03*
Y1963268D03*
X886417Y191614D03*
Y341220D03*
Y597126D03*
Y746732D03*
Y1002638D03*
Y1152244D03*
Y1408150D03*
Y1557756D03*
Y1813662D03*
Y1963268D03*
G54D29*
X9843Y153168D03*
Y265767D03*
Y353144D03*
Y717711D03*
Y762617D03*
Y875216D03*
Y1137420D03*
Y1250019D03*
Y1337396D03*
Y1701963D03*
Y1746869D03*
Y1859468D03*
G54D26*
X45300Y1737100D03*
X97200Y513400D03*
G54D31*
X1019291Y1416024D03*
Y1694212D03*
G54D28*
X78749Y664550D03*
G54D27*
X32299Y1497550D03*
G54D19*
X129920Y17716D03*
X994093Y1889751D03*
G54D15*
X8750Y1086250D03*
X8499Y1937550D03*
X5303Y1947050D03*
X11703Y1951946D03*
X74499Y84050D03*
Y80650D03*
X86899Y130567D03*
X86599Y126750D03*
X74999Y74050D03*
Y70550D03*
X78700Y70700D03*
Y74200D03*
X15750Y102250D03*
X65999Y216050D03*
X95350Y204550D03*
X89800Y208550D03*
X26299Y383854D03*
Y387629D03*
X28100Y374000D03*
X26492Y439350D03*
X26599Y442749D03*
X26299Y399601D03*
Y403376D03*
Y478404D03*
X26899Y454850D03*
X26515Y481798D03*
X45800Y405200D03*
X26799Y458497D03*
X26486Y462648D03*
X26499Y466250D03*
X64403Y471046D03*
X64397Y474446D03*
X26524Y426720D03*
X26399Y423322D03*
X61400Y452600D03*
X35900Y412600D03*
X65000Y455500D03*
X28900Y417800D03*
X39217Y554750D03*
X42867Y548450D03*
X43099Y555850D03*
X33699Y561850D03*
X46299Y552950D03*
X36499Y517775D03*
Y521550D03*
X26399Y501966D03*
Y505741D03*
X64600Y486300D03*
X64700Y489700D03*
X33307Y557938D03*
X26199Y547176D03*
X29999Y557150D03*
X26599Y525648D03*
X95500Y513400D03*
X26599Y529302D03*
X60003Y534150D03*
X86199Y536025D03*
X59999Y537550D03*
X86199Y532250D03*
X65599Y514250D03*
X49799Y559150D03*
X68000Y546500D03*
X72500Y545000D03*
X27199Y539600D03*
X42202Y608195D03*
X39600Y626984D03*
X41400Y611500D03*
X42709Y625607D03*
X38300Y633800D03*
X41500Y642800D03*
X27499Y620203D03*
Y623857D03*
X36499Y566350D03*
X37999Y611550D03*
X42599Y567850D03*
X26568Y635950D03*
Y639604D03*
X47101Y632355D03*
X28000Y578500D03*
X25581Y567763D03*
X47626Y611300D03*
X45701Y607700D03*
X27699Y573750D03*
X82499Y627050D03*
X26800Y611500D03*
X41500Y635000D03*
X52500D03*
X48999Y642900D03*
X81251Y607249D03*
Y619251D03*
X28808Y593150D03*
X28700Y596549D03*
X32200Y603710D03*
X31598Y607102D03*
X80499Y664550D03*
X26737Y651957D03*
X26999Y656550D03*
X27687Y667447D03*
Y671101D03*
X76999Y664550D03*
X27700Y682700D03*
X50410Y695801D03*
X50300Y699200D03*
X44046Y799554D03*
X32800Y803050D03*
X46887Y803413D03*
X37416Y799033D03*
X37099Y811350D03*
X51100Y806300D03*
X49900Y813200D03*
X56281Y801350D03*
X27299Y783550D03*
X35300Y789375D03*
X35559Y795112D03*
X45100Y793100D03*
X37216Y807951D03*
X76540Y850938D03*
X29299Y836901D03*
X75500Y847700D03*
X49300Y836500D03*
X46700Y820100D03*
X40400Y840792D03*
X89000Y816500D03*
X48346Y844529D03*
X58699Y837250D03*
X68860Y838706D03*
X90000Y826000D03*
X54074Y815750D03*
X69499Y842950D03*
X62405Y820300D03*
X63499Y843050D03*
X90500Y831500D03*
X31699Y814350D03*
X65500Y817700D03*
X23299Y863050D03*
X26662Y861550D03*
X39649Y822000D03*
X80500Y817000D03*
X74220Y854150D03*
X72362Y849550D03*
X25000Y858100D03*
X46576Y832951D03*
X29600Y854000D03*
X24000Y853500D03*
X94999Y901550D03*
X85999Y940429D03*
X86399Y937050D03*
X29000Y896500D03*
X72000Y1013400D03*
X63273Y1023974D03*
X90000Y993100D03*
X92600Y996100D03*
X80699Y1004450D03*
Y1000450D03*
X66499Y1025050D03*
X75900Y1019100D03*
X63500Y1029600D03*
X88000Y1008500D03*
X75500Y1012261D03*
X76999Y1196550D03*
X21817Y1156317D03*
X25507Y1372045D03*
X25558Y1368447D03*
X86890Y1346635D03*
Y1342860D03*
X28499Y1391050D03*
X32333Y1389383D03*
X20999Y1352050D03*
Y1320550D03*
X77758Y1357742D03*
X25000D03*
X30378Y1462518D03*
X33915Y1462681D03*
X32094Y1448448D03*
X28697Y1448296D03*
X32451Y1411468D03*
X28999Y1411550D03*
X33206Y1432352D03*
X30499Y1434550D03*
X30500Y1395500D03*
X76000Y1431100D03*
X34896Y1555730D03*
X34099Y1497550D03*
X30499D03*
X80043Y1544691D03*
X83932Y1544705D03*
X29631Y1533063D03*
X31999Y1517846D03*
Y1521500D03*
X46700Y1546793D03*
X34465Y1481683D03*
X30999Y1482050D03*
X44299Y1550950D03*
X96200Y1550100D03*
X37999Y1530900D03*
X38500Y1534600D03*
X32099Y1535550D03*
X30115Y1511900D03*
X33512Y1512051D03*
X90324Y1538800D03*
X26705Y1534795D03*
X30199Y1545450D03*
X24199Y1523700D03*
X79000Y1555500D03*
X82429D03*
X36340Y1558809D03*
X78600Y1561900D03*
X29499Y1630050D03*
X75000Y1561800D03*
X28899Y1613524D03*
X42199Y1601050D03*
X38208Y1569841D03*
X25521Y1563350D03*
X30520Y1572049D03*
X32299Y1613524D03*
X34599Y1595300D03*
X32663Y1628181D03*
X27123Y1572205D03*
X33599Y1600200D03*
X74800Y1584700D03*
X74700Y1574600D03*
X39000Y1573500D03*
X89373Y1561073D03*
X85600Y1561500D03*
X80400Y1571766D03*
X82329Y1568117D03*
X31999Y1661127D03*
X28600Y1661039D03*
X29626Y1645002D03*
X33026Y1645051D03*
X95499Y1665418D03*
X93999Y1703050D03*
X74500Y1692000D03*
X21600Y1702900D03*
X32700Y1673300D03*
X32494Y1669706D03*
X29100Y1669500D03*
X30274Y1787238D03*
X85599Y1797350D03*
X38878Y1799571D03*
X47899Y1798650D03*
X36300Y1805123D03*
X35675Y1783450D03*
X39324Y1780623D03*
X39000Y1750800D03*
X43751Y1780559D03*
X42275Y1754000D03*
X48049Y1791450D03*
X85341Y1752245D03*
X85194Y1748848D03*
X46999Y1779550D03*
X37699Y1789850D03*
X46199Y1783050D03*
X74400Y1778100D03*
X38094Y1785840D03*
X41200Y1747050D03*
X42199Y1792250D03*
X37574Y1794050D03*
X45799Y1757650D03*
X46799Y1794900D03*
X47440Y1761391D03*
X31811Y1790271D03*
X47400Y1765250D03*
X43559Y1767884D03*
X40478Y1795820D03*
X32099Y1797150D03*
X47604Y1769005D03*
X45782Y1771877D03*
X47499Y1775350D03*
X45877Y1728477D03*
Y1724823D03*
X47000Y1737100D03*
X43600D03*
X28550Y1828153D03*
X29599Y1844350D03*
X29899Y1821050D03*
X34099Y1822850D03*
X80099Y1817250D03*
X28123Y1831527D03*
X35876Y1812350D03*
X34129Y1815267D03*
X86649Y1817100D03*
X61009Y1822340D03*
X36532Y1825352D03*
X36399Y1828750D03*
X26099Y1824950D03*
X25999Y1842550D03*
X46499Y1836550D03*
X47166Y1839884D03*
X80999Y1836550D03*
X90000Y1827900D03*
X43099Y1833850D03*
X39699D03*
X93500Y1827900D03*
X40500Y1863000D03*
X22367Y1836633D03*
X15099Y1944050D03*
X50499Y1961550D03*
X14999Y1936050D03*
X17499Y1961050D03*
X43462Y1961160D03*
X32999Y1960555D03*
X23030Y1922038D03*
X25499Y1956050D03*
X42499Y1902550D03*
X48499Y1897050D03*
X26765Y1921945D03*
X57999Y1891050D03*
X31799Y1979050D03*
X97499Y90050D03*
X115876Y125973D03*
Y130050D03*
X174999Y79050D03*
X175499Y86572D03*
X178999Y79050D03*
X176399Y94872D03*
X173500Y166315D03*
X154200Y168500D03*
X149400Y166400D03*
X149999Y243504D03*
Y239729D03*
X122397Y252688D03*
X122799Y249150D03*
X141499Y427550D03*
X165500Y416500D03*
X141499Y423050D03*
X159600Y446399D03*
X152000Y520813D03*
X171722Y513827D03*
X163549Y517100D03*
X140940Y561800D03*
X150500Y545000D03*
X135499Y517550D03*
X107499Y497050D03*
X98900Y513400D03*
X172499Y491053D03*
X137899Y545451D03*
X176799Y493850D03*
X150750Y540416D03*
X109400Y543200D03*
X149000Y537500D03*
X106000Y543200D03*
X156500Y554000D03*
X138416Y553500D03*
X125499Y635550D03*
Y638950D03*
X127999Y645550D03*
X131400Y644600D03*
X144238Y645356D03*
X107000Y604800D03*
X105100Y600000D03*
X157000Y573851D03*
X141300Y565900D03*
X160824Y577000D03*
X144238Y649131D03*
X111200Y799450D03*
X110195Y809979D03*
X110500Y790200D03*
X110700Y795700D03*
X109831Y806598D03*
X109700Y803200D03*
X110202Y813379D03*
X154799Y838050D03*
X165499Y815550D03*
X110499Y834550D03*
X169106Y815865D03*
X153900Y832200D03*
X98700Y842600D03*
Y822550D03*
X98000Y833500D03*
X163500Y937100D03*
X172500Y919294D03*
X108200Y963600D03*
X172000Y931600D03*
X153499Y918550D03*
X108845Y931657D03*
X109099Y928250D03*
X171100Y935000D03*
X102100Y968500D03*
X99000Y965000D03*
X172000Y961000D03*
X152500Y960000D03*
X170250Y948500D03*
X154749Y968249D03*
X171000Y939500D03*
X123999Y1054050D03*
Y1050650D03*
X112699Y1058974D03*
X104600Y980500D03*
X154749Y979149D03*
X103200Y985364D03*
X104700Y989900D03*
X120749Y1093990D03*
X164700Y1085400D03*
X105499Y1080550D03*
X106718Y1076050D03*
X105999Y1085800D03*
X101499Y1072550D03*
X125900Y1091282D03*
X132499Y1094550D03*
X123999Y1102550D03*
X138600Y1124600D03*
X116700Y1063500D03*
X105600Y1069500D03*
X108999Y1102050D03*
X137481Y1077557D03*
X137477Y1081177D03*
X124423Y1077523D03*
Y1081177D03*
X106999Y1194550D03*
X102900Y1196050D03*
X103686Y1223863D03*
X103999Y1216863D03*
X127000Y1202000D03*
X148000Y1206000D03*
X106162Y1205702D03*
X123970Y1221573D03*
X119399Y1298113D03*
X101541Y1262607D03*
X116999Y1288050D03*
X101399Y1292550D03*
X107999Y1307713D03*
X120507Y1317050D03*
X116499Y1328013D03*
X120507Y1328096D03*
X135850Y1322250D03*
X143700Y1332500D03*
X112440Y1358196D03*
X112999Y1361550D03*
X97229Y1373337D03*
X97000Y1377600D03*
X109228Y1337090D03*
Y1333315D03*
X102700Y1321363D03*
X119499Y1339050D03*
X121000Y1364000D03*
X148024Y1333525D03*
X140000Y1332600D03*
X129000Y1356500D03*
X113500Y1344500D03*
Y1348154D03*
X102350Y1344500D03*
Y1348154D03*
X147400Y1321600D03*
X125100Y1366000D03*
X124290Y1469241D03*
X123808Y1465050D03*
X117390Y1426201D03*
Y1429976D03*
X104935Y1440634D03*
X142999Y1456373D03*
X104999Y1444941D03*
X106999Y1454450D03*
X100699Y1471050D03*
X142900Y1460000D03*
X100800Y1536450D03*
X98599Y1491350D03*
X99899Y1539850D03*
X100000Y1546650D03*
X97499Y1554550D03*
X96999Y1558050D03*
X98144Y1534309D03*
X157400Y1596550D03*
X160200Y1598500D03*
X150999Y1713550D03*
X171999Y1662250D03*
X131999Y1710050D03*
X117499Y1706050D03*
X128749Y1703300D03*
X169100Y1685800D03*
X133090Y1699959D03*
X174250Y1694500D03*
X109499Y1712213D03*
X112753Y1716613D03*
X152633Y1677967D03*
X122642Y1704243D03*
X112562Y1720613D03*
X135499Y1710150D03*
X118499Y1694050D03*
X123749Y1711550D03*
X177900Y1690400D03*
X169600Y1682300D03*
X109499Y1743550D03*
X109399Y1739550D03*
X99199Y1761899D03*
X99999Y1753575D03*
X141999Y1764550D03*
X110099Y1759875D03*
X101399Y1784700D03*
X165900Y1790500D03*
X161900Y1793400D03*
X123393Y1870859D03*
X137999Y1861497D03*
Y1865151D03*
X123592Y1874254D03*
X96600Y1826000D03*
X97999Y1843050D03*
X186999Y99050D03*
X213499Y104650D03*
X223499Y108150D03*
X188999Y120800D03*
X205499Y105550D03*
X225499Y68550D03*
X233749Y110800D03*
X230749Y76300D03*
X207999Y109550D03*
X237899Y107050D03*
X218499Y190550D03*
X247800Y269700D03*
X225298Y281114D03*
X253871Y291410D03*
X250300Y275100D03*
X250400Y283100D03*
X239600Y278600D03*
X187699Y492850D03*
X199900Y554050D03*
X220000Y516400D03*
X183499Y556100D03*
X188000Y484500D03*
X246800Y677100D03*
X254499Y697700D03*
X249700Y682500D03*
X249800Y689900D03*
X238500Y680800D03*
X211750Y894600D03*
X200799Y896600D03*
X233500Y1066100D03*
X226800Y1093400D03*
X221800Y1069300D03*
X247500Y1085500D03*
X251500Y1136700D03*
X229800Y1073600D03*
X242000Y1066000D03*
X182500Y1275500D03*
X199149Y1362900D03*
X194700Y1385700D03*
X181000Y1365500D03*
X180500Y1369900D03*
X229025Y1471576D03*
X241000Y1469600D03*
X224750Y1483950D03*
X233700Y1481600D03*
X199500Y1627000D03*
X195000Y1645500D03*
X179999Y1644500D03*
X181100Y1682700D03*
X201499Y1781050D03*
X227814Y1887513D03*
X231800Y1887100D03*
X229800Y1875700D03*
X218100Y1886400D03*
X213138Y1952703D03*
X249499Y1928050D03*
X231999Y1914050D03*
X210999Y1942050D03*
X223436Y1890465D03*
X214999Y1909550D03*
X257499Y1911050D03*
X249600Y1896800D03*
X341499Y63050D03*
Y67110D03*
X343499Y31650D03*
X308999Y87050D03*
X323400Y105200D03*
X282800Y87500D03*
X297499Y97550D03*
X315800Y100500D03*
X324800Y89400D03*
X293999Y293550D03*
X326499Y334054D03*
X284999Y338650D03*
X281499Y338550D03*
X326499Y337454D03*
X301249Y346050D03*
X344520Y406329D03*
X279939Y728610D03*
X329499Y801550D03*
X330540Y795509D03*
X327999Y740550D03*
X320499Y798050D03*
X285499Y745050D03*
X282099D03*
X327749Y744050D03*
X306500Y753550D03*
X340699Y1046086D03*
X269500Y1135500D03*
X282500Y1135000D03*
X283499Y1556050D03*
X279999D03*
X326500Y1550200D03*
X261999Y1516050D03*
X295000Y1513000D03*
X333000Y1578000D03*
X330300Y1561200D03*
X310249Y1569800D03*
X264499Y1964050D03*
X331622Y1944767D03*
X288709Y1948042D03*
X284999Y1947691D03*
X342999Y1947409D03*
X342621Y1943409D03*
X330500Y1966500D03*
X332103Y1948133D03*
X310499Y1957050D03*
X285499Y1930050D03*
X381999Y57050D03*
Y53550D03*
X394199Y45050D03*
X358999Y61550D03*
X354999Y72050D03*
X371700Y85500D03*
X400499Y406329D03*
X371999Y549300D03*
X394649Y630600D03*
X350499Y597300D03*
X375999Y698550D03*
X350499Y715050D03*
X371500Y880600D03*
X364499Y1099050D03*
X372999Y1123550D03*
X345499Y1096550D03*
X370149Y1320050D03*
X345424Y1310050D03*
X347324Y1524000D03*
X366149Y1554050D03*
X402499Y1476850D03*
X390999Y1514398D03*
Y1517798D03*
X349774Y1582900D03*
X354500Y1559500D03*
X400999Y1575550D03*
X354000Y1584900D03*
X353499Y1710450D03*
X377900Y1703800D03*
X348499Y1762050D03*
X385499Y1735050D03*
X645549Y1815134D03*
X644360Y1819137D03*
X757499Y1079550D03*
X757999Y1484050D03*
X750000Y1560500D03*
X732549Y1806634D03*
X733149Y1798634D03*
X707600Y1815600D03*
X733049Y1814134D03*
X711652Y1822109D03*
X711848Y1825504D03*
X758499Y1893550D03*
X829917Y216200D03*
X833576Y215432D03*
X837999Y219550D03*
X822100Y279500D03*
X827500Y274500D03*
X809940Y264940D03*
X822100Y261700D03*
X816700Y274300D03*
X791499Y333050D03*
X789999Y336550D03*
X772499Y323050D03*
X772873Y326924D03*
X780499Y330050D03*
X771105Y722789D03*
X829800Y666650D03*
X781999Y725550D03*
X808660Y667540D03*
X820600Y664300D03*
X813200Y675900D03*
X788999Y736050D03*
X791999Y733050D03*
X769999D03*
X792154Y1135926D03*
X825700Y1083100D03*
X771999Y1124550D03*
X772499Y1130050D03*
X789499Y1138050D03*
X779499Y1131050D03*
X807000Y1072900D03*
X825800Y1072300D03*
X815400Y1078800D03*
X803199Y1151850D03*
X822100Y1466800D03*
X774542Y1530050D03*
X804899Y1556950D03*
X827700Y1487600D03*
X774577Y1533796D03*
X791499Y1543550D03*
X793999Y1541050D03*
X784499Y1529050D03*
X809960Y1478040D03*
X814700Y1486300D03*
X793000Y1803500D03*
X795849Y1805500D03*
X828500Y1877800D03*
X807000Y1822300D03*
X803500Y1822708D03*
X810900Y1882440D03*
X822700Y1871100D03*
X805900Y1887560D03*
X771499Y1936550D03*
X802499Y1951550D03*
X800431Y1941193D03*
X771499Y1940050D03*
X802099Y1961950D03*
X834799Y1946950D03*
X792499Y1949050D03*
X794499Y1941050D03*
X782999Y1937050D03*
X907499Y131800D03*
X902499Y110550D03*
X901499Y92050D03*
X898999Y110550D03*
X897555Y90494D03*
X910999Y124550D03*
X916499Y172550D03*
X867500Y163924D03*
X867576Y159924D03*
X878078Y240103D03*
Y243878D03*
X854400Y264600D03*
X847878Y250040D03*
X851278Y249974D03*
X842499Y280924D03*
X868799Y294750D03*
X865499Y288050D03*
X867899Y321550D03*
X868299Y336150D03*
X902999Y556050D03*
X878596Y645573D03*
X879750Y570550D03*
X879950Y565050D03*
X851172Y655432D03*
X878596Y649348D03*
X847772Y655370D03*
X852696Y671197D03*
X900499Y962100D03*
X879708Y971892D03*
X878233Y1051095D03*
X877964Y1054485D03*
X850833Y1061441D03*
X847233Y1061492D03*
X900999Y979050D03*
X883083Y979183D03*
X864499Y1128750D03*
X852333Y1077716D03*
X861849Y1376050D03*
X866700Y1379796D03*
X866596Y1375796D03*
X848888Y1466402D03*
X852288Y1466346D03*
X878054Y1456450D03*
X877853Y1459991D03*
X867523Y1542821D03*
X867199Y1535150D03*
X854327Y1477550D03*
X863699Y1501250D03*
X886439Y1717600D03*
X862800Y1712700D03*
X889800Y1711500D03*
X917499Y1796550D03*
X879700Y1786300D03*
X873300Y1740100D03*
X879664Y1782213D03*
X866914Y1861840D03*
X853499Y1871036D03*
X866914Y1865615D03*
X850099Y1871056D03*
X854814Y1883550D03*
X863699Y1906450D03*
X857099Y1917650D03*
X930999Y115550D03*
X937999Y122050D03*
X938499Y115550D03*
X961499Y93350D03*
X926999Y122050D03*
X943499Y82550D03*
X934499Y118750D03*
X926999Y115050D03*
X986400Y1639302D03*
X987100Y1624900D03*
X981200Y1625800D03*
X964000Y1639200D03*
X960900Y1636400D03*
X969600Y1638300D03*
X977500Y1660500D03*
X978000Y1668000D03*
X967600Y1651100D03*
X974000Y1670700D03*
X984211Y1667500D03*
X971558Y1646500D03*
X981500Y1653000D03*
X980800Y1659600D03*
X982050Y1649302D03*
G54D20*
X167323Y179803D03*
Y353031D03*
Y585315D03*
Y758543D03*
Y990827D03*
Y1164055D03*
Y1396339D03*
Y1569567D03*
Y1801851D03*
Y1975079D03*
X895669Y179803D03*
Y353031D03*
Y585315D03*
Y758543D03*
Y990827D03*
Y1164055D03*
Y1396339D03*
Y1569567D03*
Y1801851D03*
Y1975079D03*
G54D14*
X6500Y1098000D03*
Y1103500D03*
Y1110000D03*
Y1116500D03*
X92999Y52050D03*
X88000Y36400D03*
X93000Y44900D03*
X92900Y39700D03*
X32400Y115400D03*
X37000Y115300D03*
X32300Y121000D03*
X36900Y120900D03*
X32100Y130700D03*
X37000D03*
X32100Y136600D03*
X36800Y136700D03*
X36500Y179000D03*
Y188500D03*
X35000Y198500D03*
X30000Y179000D03*
X23500D03*
X30000Y188500D03*
X24000D03*
X29000Y198000D03*
X23500D03*
X94500Y456800D03*
X93499Y481550D03*
Y477050D03*
X93199Y449850D03*
X93500Y445300D03*
X94499Y486550D03*
X44000Y728500D03*
X40000Y729000D03*
X43499Y657550D03*
X44500Y733000D03*
X40000D03*
X43999Y737550D03*
X39999Y738050D03*
X44499Y742050D03*
X39999D03*
X93299Y862050D03*
X93690Y887139D03*
X93900Y882400D03*
X94001Y856895D03*
X93808Y852063D03*
X93499Y892050D03*
X67000Y1011500D03*
X22500Y1183000D03*
Y1176500D03*
Y1170000D03*
Y1164500D03*
X83499Y1602050D03*
X92499Y1589050D03*
X86999D03*
X83499Y1594050D03*
Y1598050D03*
X74999Y1602050D03*
X78999D03*
X81499Y1589050D03*
X78999Y1593550D03*
X74999Y1598050D03*
Y1593550D03*
X78999Y1598050D03*
X82999Y1887550D03*
X78999D03*
X58999Y1958050D03*
X82499Y1957050D03*
X73499D03*
X66499D03*
X92499Y1959050D03*
X47499Y1915050D03*
X62999Y1914550D03*
Y1926050D03*
X81499Y1915550D03*
X47499Y1930550D03*
X62499Y1939550D03*
X73499Y1945550D03*
X83999Y1945050D03*
X78999Y1891550D03*
X82999D03*
X78999Y1896050D03*
X78433Y1900010D03*
X78999Y1904050D03*
X83499Y1896050D03*
X83433Y1904010D03*
X83999Y1900050D03*
X96999Y49550D03*
X97800Y36000D03*
X96900Y40400D03*
X167499Y43550D03*
X116400Y56000D03*
X129100Y55900D03*
X127499Y65050D03*
X141999Y65550D03*
X156499Y66050D03*
X129999Y78050D03*
X166999Y88050D03*
X166499Y83550D03*
Y79050D03*
X158499D03*
Y84050D03*
Y88550D03*
Y93550D03*
X166999Y92550D03*
Y97050D03*
X127999Y99550D03*
X165499Y106050D03*
X169999Y103050D03*
X114800Y68500D03*
X97999Y199050D03*
X155999Y181050D03*
X137100Y436800D03*
X129400Y426900D03*
X135999Y472550D03*
X135140Y478930D03*
X100500Y456700D03*
X97699Y477050D03*
Y481550D03*
X149700Y471600D03*
X154100Y476500D03*
X164600Y476700D03*
X171300D03*
X97999Y445550D03*
X97699Y449850D03*
X147300Y526700D03*
X147590Y521500D03*
X145649Y509550D03*
X136349Y509050D03*
X98999Y488050D03*
X140499Y499050D03*
X153499Y502550D03*
X148999D03*
X136299Y499050D03*
X152499Y810550D03*
X161999Y768050D03*
X152499Y816050D03*
Y820550D03*
Y825050D03*
X156499Y876050D03*
Y870550D03*
X97499Y862050D03*
X155499Y891050D03*
Y896050D03*
X97700Y887400D03*
X97900Y882400D03*
X163999Y863050D03*
X159999D03*
X155999Y859050D03*
Y863050D03*
X97800Y851800D03*
X98001Y856950D03*
X97499Y892550D03*
X151999Y936550D03*
X152499Y931550D03*
X159459Y896616D03*
X163499Y896550D03*
X157499Y909050D03*
Y904550D03*
X159186Y946117D03*
X151300Y1049300D03*
X100999Y1099550D03*
X105000Y1100500D03*
X100999Y1095050D03*
X105006Y1095366D03*
X110999Y1130550D03*
X115200Y1130300D03*
X110999Y1126050D03*
Y1122050D03*
Y1118050D03*
X114999Y1126050D03*
Y1122050D03*
Y1118050D03*
X144149Y1226113D03*
Y1222113D03*
X148499D03*
Y1226113D03*
X144149Y1230113D03*
X148486D03*
X175823Y1297070D03*
X175499Y1302113D03*
Y1306113D03*
Y1292550D03*
X123500Y1360300D03*
X105749Y1712749D03*
X172499Y1714050D03*
X167499Y1714113D03*
X162499D03*
X130499Y1730050D03*
X128000Y1735000D03*
X144499Y1729550D03*
X139500Y1730500D03*
X133000Y1734500D03*
X170499Y1731050D03*
X165499Y1730613D03*
X172499Y1726613D03*
X167999D03*
X163499D03*
X132700Y1972400D03*
X137900Y1972200D03*
X126500Y1972400D03*
X131100Y1908500D03*
X129600Y1912400D03*
X124433Y1908510D03*
X124999Y1912550D03*
X98433Y1940510D03*
X98999Y1944550D03*
X102433Y1940555D03*
X103433Y1944510D03*
X132700Y1978600D03*
X137900Y1978400D03*
X126600Y1978500D03*
X119999Y1978550D03*
X119499Y1972550D03*
X189499Y39150D03*
X197999Y39900D03*
X193999D03*
X208499Y45650D03*
X199999Y46050D03*
X194499Y44050D03*
X225499Y52550D03*
Y46550D03*
Y63550D03*
Y58050D03*
X183499Y45550D03*
X192499Y57550D03*
X227499Y192050D03*
X231999D03*
X227999Y187050D03*
X231999D03*
X227999Y182550D03*
X231999D03*
X227999Y178050D03*
X231999D03*
X179999Y442550D03*
X179649Y438550D03*
X183999D03*
Y442550D03*
Y447050D03*
X179999D03*
X194999Y490050D03*
X190499Y487550D03*
X191199Y491550D03*
X187499Y531613D03*
Y536113D03*
X193499Y541113D03*
X188999D03*
X193499Y549613D03*
X188999D03*
Y545613D03*
X193999Y545550D03*
X215999Y887550D03*
X220499D03*
X215499Y883550D03*
X204496Y846111D03*
X204649Y838050D03*
X208999D03*
X209000Y846113D03*
X204649Y842113D03*
X208986D03*
X219499Y939613D03*
Y948613D03*
Y943813D03*
X214999Y939613D03*
Y944113D03*
Y948613D03*
X219499Y926613D03*
X214999D03*
X259999Y1152992D03*
X259499Y1161550D03*
X179999Y1306050D03*
Y1301550D03*
Y1292550D03*
Y1296613D03*
X260999Y1503550D03*
X180299Y1626550D03*
X180000Y1619600D03*
X195700Y1619100D03*
X195600Y1623700D03*
X180299Y1634550D03*
X179733Y1630590D03*
X226999Y1941050D03*
X289499Y39050D03*
X286603Y34928D03*
X290999Y67550D03*
X300700Y39400D03*
X304500Y44500D03*
X305100Y39700D03*
X294100Y28000D03*
X308900Y41000D03*
X308800Y46400D03*
X289999Y72550D03*
X288499Y76550D03*
X289499Y80550D03*
X308499Y72550D03*
X303999Y74050D03*
X307999Y78550D03*
X279998Y308614D03*
Y304114D03*
Y299614D03*
Y295114D03*
X267498Y310114D03*
Y305114D03*
Y300114D03*
Y295114D03*
X305998Y352114D03*
X293998Y361114D03*
Y356614D03*
Y352114D03*
X289998Y361114D03*
Y356614D03*
Y352114D03*
X268499Y716550D03*
Y711550D03*
Y701550D03*
Y706550D03*
X280999Y717550D03*
X280433Y713590D03*
X280999Y701550D03*
Y705550D03*
X294999Y767050D03*
X290999D03*
X294999Y762550D03*
Y758050D03*
X290999Y762550D03*
Y758050D03*
X306999D03*
X272499Y1153050D03*
X268499D03*
X263999D03*
X271999Y1161550D03*
X267999D03*
X263499D03*
X267349Y1518150D03*
Y1522550D03*
X266999Y1512550D03*
X267349Y1527172D03*
X279499Y1510550D03*
Y1515050D03*
X279075Y1525957D03*
X278567Y1529925D03*
X305998Y1569114D03*
X293998Y1578114D03*
Y1573614D03*
Y1569114D03*
X289998Y1578114D03*
Y1573614D03*
Y1569114D03*
X334999Y1797050D03*
X326301Y1766030D03*
X306999Y1932550D03*
X302499D03*
X298499D03*
X293999Y1933050D03*
X306000Y1961500D03*
X305500Y1965500D03*
X293999Y1971050D03*
Y1966550D03*
Y1962050D03*
X289499Y1961550D03*
Y1966550D03*
Y1971050D03*
X281999Y1918550D03*
Y1923550D03*
Y1928550D03*
X266999Y1915550D03*
Y1920050D03*
Y1924550D03*
Y1929050D03*
Y1933550D03*
X381499Y65550D03*
X376999D03*
X371999Y15550D03*
X376499D03*
X380999D03*
X369999Y23550D03*
Y19050D03*
X382499Y20050D03*
X381499Y70050D03*
X376999D03*
X360999Y113050D03*
X356499D03*
X351999D03*
X347499D03*
X360999Y100550D03*
X355999D03*
X350999D03*
X345999D03*
X558099Y335050D03*
X557933Y331010D03*
X557999Y322550D03*
Y326550D03*
X558499Y616050D03*
X554304Y615840D03*
X554499Y624550D03*
X558699D03*
X554499Y620050D03*
X558709Y620245D03*
X563499Y1497550D03*
Y1486550D03*
Y1503550D03*
Y1492050D03*
X544300Y1784638D03*
X633837Y1807384D03*
X757999Y154550D03*
Y159050D03*
X753999Y154550D03*
Y159050D03*
X755499Y314550D03*
X751539Y313984D03*
X755346Y319149D03*
X751499Y318050D03*
X748000Y357500D03*
X751499Y679148D03*
X749499Y716050D03*
X744999Y715550D03*
X749999Y720050D03*
X745499D03*
X750000Y755500D03*
X755499Y1119050D03*
X749999Y1119550D03*
X748999Y1115550D03*
X748499Y1111550D03*
X747000Y1159000D03*
X751000Y1517000D03*
X757500Y1522500D03*
X751000Y1521000D03*
Y1525000D03*
X751999Y1775550D03*
X756617Y1780067D03*
X752657Y1779496D03*
X755999Y1775550D03*
X756900Y1766000D03*
X753558Y1769946D03*
X757518Y1770517D03*
X752900Y1766000D03*
X717000Y1812384D03*
X750000Y1965500D03*
X840499Y55050D03*
X839999Y46050D03*
X840999Y62550D03*
X837999Y91050D03*
X838999Y85050D03*
X838499Y99550D03*
Y107050D03*
X839499Y119050D03*
X841499Y71550D03*
X809373Y307571D03*
Y297571D03*
Y292571D03*
X808999Y303050D03*
X796873Y307571D03*
Y303071D03*
Y298571D03*
Y294071D03*
X784478Y355424D03*
Y359924D03*
X781478Y363924D03*
X776978D03*
X772478Y359924D03*
Y363924D03*
X806831Y701853D03*
Y706853D03*
Y711853D03*
X794331Y698353D03*
Y702853D03*
Y707353D03*
Y711853D03*
X806999Y697050D03*
X771196Y764382D03*
Y760382D03*
X775696Y764382D03*
X780196D03*
X783196Y760382D03*
Y755882D03*
X799385Y761436D03*
X811499Y1097050D03*
X807499D03*
X807341Y1116216D03*
Y1111216D03*
Y1101216D03*
X806999Y1106050D03*
X802499Y1097566D03*
X798499D03*
X783333Y1157392D03*
Y1161892D03*
X780333Y1165892D03*
X775833D03*
X771333Y1161892D03*
Y1165892D03*
X809245Y1518722D03*
Y1508722D03*
Y1503722D03*
X795999Y1518550D03*
Y1514050D03*
Y1509550D03*
Y1504550D03*
X808999Y1513550D03*
X785827Y1561296D03*
Y1565796D03*
X782827Y1569796D03*
X778327D03*
X773327Y1565796D03*
X773827Y1569796D03*
X767159Y1792364D03*
X773999Y1923550D03*
X767999Y1923050D03*
X774499Y1930050D03*
X768999D03*
X783814Y1967213D03*
Y1971713D03*
X795526Y1909696D03*
X795493Y1913696D03*
X795501Y1917696D03*
X795499Y1922050D03*
X807997Y1922865D03*
X808005Y1918865D03*
X807936Y1914865D03*
Y1910365D03*
X784016Y1975708D03*
X775814Y1975699D03*
X771814Y1975713D03*
X902999Y22050D03*
X917499Y21550D03*
X909499D03*
X902499Y35050D03*
X909999Y35550D03*
X916499Y36050D03*
X854499Y39550D03*
X865499D03*
X883999Y39050D03*
X904999Y61550D03*
Y67550D03*
X905499Y56550D03*
X843499Y82550D03*
X855499Y82050D03*
X876999D03*
X867499D03*
X845999Y111050D03*
X886499Y99550D03*
Y104550D03*
X890459Y100116D03*
X890499Y104550D03*
X865499Y125550D03*
X875499D03*
X856499Y71050D03*
X881499Y70550D03*
X866999D03*
X904499Y74050D03*
X903999Y574378D03*
X866499Y724550D03*
X873499Y1356050D03*
X882200Y1744800D03*
X886400Y1744400D03*
X904814Y1789113D03*
X864414Y1940050D03*
X945499Y33550D03*
X940499Y33050D03*
X929999Y32550D03*
X928499Y51550D03*
X943499Y48050D03*
Y55050D03*
X928999Y56050D03*
X928499Y60550D03*
X928999Y65550D03*
X942999Y61550D03*
Y66550D03*
X943499Y72550D03*
Y78050D03*
X973500Y1474000D03*
X971500Y1467500D03*
X971700Y1457800D03*
Y1462300D03*
X972000Y1442000D03*
Y1437500D03*
X971700Y1448300D03*
Y1452800D03*
X962500Y1436500D03*
Y1441000D03*
X952800Y1437500D03*
Y1442000D03*
X962000Y1466500D03*
X966000Y1475000D03*
X952300Y1467500D03*
X958800Y1472500D03*
X962200Y1447300D03*
Y1451800D03*
X952500Y1448300D03*
Y1452800D03*
X962200Y1456800D03*
Y1461300D03*
X952500Y1457800D03*
Y1462300D03*
X972549Y1502300D03*
Y1506800D03*
X973500Y1483000D03*
Y1478500D03*
X973200Y1488300D03*
X972700Y1497300D03*
X966000Y1479500D03*
Y1484000D03*
X958800Y1477000D03*
Y1481500D03*
X965700Y1489300D03*
X960200Y1495300D03*
X958500Y1486800D03*
X951500Y1495300D03*
X960049Y1500300D03*
X951349D03*
X960049Y1504800D03*
X951349D03*
X950100Y1626100D03*
G54D22*
X210638Y62959D03*
X210634Y66863D03*
X215138Y72559D03*
X210685Y74725D03*
X210605Y70692D03*
X205938Y72528D03*
X210738Y78459D03*
Y82159D03*
X232400Y220700D03*
X210999Y221550D03*
X191999D03*
X217999Y250550D03*
X203499D03*
X185999D03*
X251499Y446050D03*
X231999Y445550D03*
X251999Y462050D03*
X232499Y461550D03*
X209499Y412550D03*
X220000Y421000D03*
X232999Y414550D03*
X252499Y415050D03*
X343999Y190050D03*
X337999Y219050D03*
X310499Y216550D03*
X290999Y216050D03*
X271999D03*
X297999Y245050D03*
X283499D03*
X265999D03*
X343499Y253550D03*
X337499Y282550D03*
X327900Y463200D03*
X306100Y462000D03*
X286999Y462050D03*
X272499Y445050D03*
X272999Y461050D03*
X269999Y415050D03*
X284499D03*
X303999Y415550D03*
X324999Y414550D03*
X333499Y483050D03*
X312499Y484050D03*
X292999Y483550D03*
X369999Y219050D03*
X382499Y190550D03*
X355499Y219050D03*
X362999Y190050D03*
X369499Y282550D03*
X381999Y254050D03*
X354999Y282550D03*
X362499Y253550D03*
X415999Y518550D03*
X444499Y283050D03*
X463999Y283550D03*
X481499D03*
X495999D03*
X448999Y255550D03*
X469999Y254550D03*
X508499Y255050D03*
X488999Y254550D03*
X438999Y381550D03*
X458499Y382050D03*
X484900Y394700D03*
X485000Y373200D03*
X509999Y382550D03*
X443499Y354050D03*
X464499Y353050D03*
X502999Y353550D03*
X483499Y353050D03*
X456499Y518050D03*
X435499Y519050D03*
X515499Y284050D03*
X536499Y283050D03*
X525999Y255050D03*
X540499D03*
X530999Y381550D03*
X520499Y353550D03*
X548100Y362200D03*
X579499Y561550D03*
X558499Y562550D03*
X538999Y562050D03*
X535499Y545050D03*
X514499Y546050D03*
X674999Y601550D03*
X646999Y584550D03*
X625999Y585050D03*
X606499Y584550D03*
X744999Y626550D03*
X721499Y617550D03*
X699999Y610050D03*
X757400Y686300D03*
X785499Y641050D03*
X777499Y638050D03*
X771800Y686600D03*
X786500Y686100D03*
X798000Y686400D03*
X777499Y664550D03*
X794999D03*
X806300Y670600D03*
X841000Y671100D03*
X923761Y85550D03*
X932961Y85581D03*
X928461Y75981D03*
X928561Y91481D03*
X928508Y87747D03*
X928428Y83714D03*
X928561Y95181D03*
X928457Y79885D03*
G54D13*
X6891Y161611D03*
X7089Y166111D03*
X8599Y751650D03*
X10999Y774050D03*
X9399Y1347350D03*
X7099Y1717750D03*
X7199Y1731450D03*
X6099Y1753750D03*
X11299Y1850050D03*
X9099Y1881550D03*
X8499Y1979550D03*
X11500Y1987000D03*
X90899Y14850D03*
X23499Y27050D03*
X50999Y21150D03*
Y47750D03*
X27799Y38450D03*
X25799Y64050D03*
X65499Y59050D03*
Y41550D03*
Y27050D03*
X40999Y42050D03*
Y27550D03*
X17600Y5604D03*
X36000D03*
X55700Y5900D03*
X73900Y6200D03*
X90900Y5800D03*
X93999Y58550D03*
X92900Y66128D03*
X52499Y145050D03*
Y130550D03*
X59499Y108050D03*
Y90550D03*
Y76050D03*
X89800Y132400D03*
X96184Y151065D03*
X71015Y123666D03*
X78165Y137116D03*
X95814Y136065D03*
X77165Y110799D03*
X92999Y86128D03*
Y96128D03*
X15302Y161500D03*
X19500D03*
X15500Y166000D03*
X19198Y152000D03*
X19698Y166000D03*
X92899Y231450D03*
X48499Y228550D03*
X23999Y229050D03*
X52499Y162550D03*
X96184Y166065D03*
X41999Y200050D03*
X23895Y238995D03*
X24300Y247300D03*
X51099Y300050D03*
X90899Y309550D03*
X93199Y279650D03*
X84899Y289250D03*
X86899Y242750D03*
X75299Y261750D03*
X42999Y275650D03*
X48499Y260550D03*
Y243050D03*
X23999Y261050D03*
Y243550D03*
X52199Y342350D03*
X89899Y368350D03*
X94199Y325550D03*
X93499Y337450D03*
X95499Y355450D03*
X89999Y396450D03*
X39999Y359550D03*
Y342050D03*
Y327550D03*
X15499Y360050D03*
Y342550D03*
Y328050D03*
X29699Y388484D03*
X29599Y382884D03*
X29999Y398684D03*
X23499Y397579D03*
X23399Y373931D03*
Y389679D03*
X23499Y381831D03*
X75300Y454100D03*
X67300Y450200D03*
X68899Y445450D03*
X87599Y403950D03*
X76099Y414250D03*
X95399Y416350D03*
X89099Y426150D03*
X29899Y404384D03*
X28900Y429200D03*
X29365Y421169D03*
X29500Y460800D03*
X28700Y451900D03*
X28800Y436700D03*
X28700Y445700D03*
X68000Y475600D03*
X67800Y469900D03*
X23499Y468447D03*
X23399Y476295D03*
Y444799D03*
X23499Y452699D03*
X23399Y460547D03*
Y429051D03*
X23499Y436951D03*
X23600Y405700D03*
X77499Y469550D03*
X93200Y510500D03*
X83700Y529500D03*
X28600Y508500D03*
X42299Y564150D03*
X62055Y561550D03*
X49555Y563550D03*
X35300Y524800D03*
X38400Y514900D03*
X88999Y538050D03*
X68900Y490600D03*
X68700Y485200D03*
X28600Y499300D03*
X26900Y532800D03*
X63499Y538550D03*
Y533050D03*
X75999Y556640D03*
X70800Y540300D03*
X22800Y539600D03*
X77165Y514650D03*
X23499Y515691D03*
X23399Y523539D03*
X23499Y531439D03*
X23399Y492043D03*
X23499Y499943D03*
X23399Y507791D03*
X23499Y484195D03*
X77999Y493050D03*
X77499Y502550D03*
X32800Y578200D03*
X47543Y578340D03*
X44959Y575756D03*
X52333Y641295D03*
X72599Y578236D03*
X39999Y576550D03*
X61099Y603236D03*
X93599Y581236D03*
X92599Y606236D03*
X30712Y624971D03*
X29999Y640550D03*
X60076Y595777D03*
X55499Y595650D03*
X29819Y634951D03*
X26869Y616861D03*
X23399Y641649D03*
X23499Y618053D03*
X23799Y625950D03*
X23499Y633801D03*
X23999Y609250D03*
X93100Y571640D03*
X22978Y588571D03*
X22699Y577950D03*
X22999Y565550D03*
X57800Y634300D03*
X34976Y619250D03*
X44900Y642800D03*
X47800Y692800D03*
X53210Y701486D03*
X30999Y656250D03*
X29999Y694550D03*
X30999Y650550D03*
X81999Y668050D03*
X74499Y662050D03*
X25999Y694870D03*
X23999Y689050D03*
X23499Y665297D03*
X23699Y673150D03*
X23499Y681045D03*
Y649549D03*
X23725Y657471D03*
X78499Y654050D03*
X90700Y792900D03*
X39899Y754850D03*
X39399Y768750D03*
X27199Y764950D03*
X28599Y775450D03*
X26399Y750850D03*
X14799Y751450D03*
X17299Y773950D03*
X79900Y791300D03*
X67999Y790400D03*
X53999Y791000D03*
X26299Y815050D03*
X26799Y874550D03*
X26099Y891650D03*
X76399Y820450D03*
X70100Y818900D03*
X92999Y868550D03*
X92499Y876550D03*
X25699Y916150D03*
X25099Y942150D03*
X23899Y957950D03*
X89400Y935400D03*
X89499Y942850D03*
X93499Y897152D03*
X93000Y907165D03*
X77499Y921550D03*
X77002Y952079D03*
X76711Y948089D03*
X77499Y962152D03*
X83988Y934028D03*
X24799Y992250D03*
X33899Y1005950D03*
X65799Y994050D03*
X72799Y982950D03*
X86900Y981600D03*
X20400Y1048300D03*
X80000Y1090500D03*
X80500Y1097550D03*
Y1104500D03*
X22447Y1223247D03*
X23200Y1209300D03*
X78499Y1273550D03*
X78613Y1282664D03*
X78779Y1302664D03*
X22321Y1231121D03*
X18099Y1343550D03*
X91279Y1340642D03*
X89999Y1348050D03*
X27499Y1387550D03*
X96000Y1369000D03*
X96100Y1384650D03*
X24499Y1389663D03*
X22851Y1374169D03*
X22999Y1366050D03*
X77166Y1353400D03*
X93316Y1351000D03*
X23700Y1354600D03*
X77165Y1327335D03*
X23499Y1381500D03*
X78779Y1312664D03*
X86165Y1339050D03*
X33000Y1393000D03*
X33400Y1408100D03*
X36198Y1446749D03*
X26800Y1443800D03*
X30600Y1415100D03*
X30999Y1438050D03*
X27999Y1430050D03*
X29100Y1459200D03*
X34200Y1466200D03*
X23028Y1468579D03*
X23499Y1460550D03*
X22999Y1453050D03*
X23499Y1445050D03*
X22999Y1437050D03*
X23999Y1429050D03*
X23499Y1421550D03*
X23999Y1413550D03*
X76499Y1507050D03*
Y1498050D03*
Y1512050D03*
Y1503050D03*
X76999Y1528050D03*
Y1519050D03*
X32700Y1485200D03*
X28999Y1478050D03*
X27100Y1494300D03*
X34900Y1501000D03*
X35400Y1522200D03*
X35999Y1514550D03*
X29600Y1515300D03*
X24423Y1527123D03*
X22999Y1500050D03*
Y1515550D03*
X23799Y1508050D03*
X24499Y1492050D03*
X23599Y1476350D03*
X23277Y1484050D03*
X25247Y1546912D03*
X90999Y1628550D03*
Y1624550D03*
X91121Y1632549D03*
X86299Y1632550D03*
X85999Y1628550D03*
Y1624550D03*
X24900Y1569500D03*
X31149Y1568300D03*
X26999Y1610550D03*
X34884Y1615734D03*
X32199Y1633124D03*
X34816Y1630953D03*
X22999Y1626050D03*
X23499Y1634050D03*
Y1618050D03*
X22699Y1594224D03*
X23499Y1610050D03*
Y1602050D03*
X23608Y1572653D03*
X24323Y1559950D03*
X31099Y1595350D03*
X33100Y1648500D03*
X47400Y1721700D03*
X15299Y1723450D03*
X15399Y1708350D03*
X34699Y1663300D03*
X27499Y1657050D03*
X26785Y1642089D03*
X22999Y1665550D03*
X92873Y1708176D03*
X24244Y1681868D03*
X22864Y1673550D03*
X23499Y1657050D03*
X23999Y1649550D03*
X23415Y1641634D03*
X92479Y1718176D03*
X78100Y1688189D03*
X92900Y1678176D03*
X40400Y1735600D03*
X47900Y1731300D03*
X47800Y1740500D03*
X14899Y1736250D03*
X15299Y1753250D03*
X89306Y1746856D03*
X89499Y1753575D03*
X84099Y1737150D03*
X83599Y1744750D03*
X77165Y1759550D03*
X93499D03*
X94336Y1773113D03*
X78529Y1788113D03*
X38600Y1880200D03*
X31400Y1885200D03*
X30400Y1849650D03*
X23999Y1857950D03*
X27199Y1874350D03*
X52999Y1871550D03*
X60449Y1842550D03*
X57499Y1871050D03*
X36100Y1892200D03*
X50299Y1946650D03*
X53999D03*
X42532Y1946783D03*
X44399Y1942250D03*
X38703Y1946754D03*
X34799Y1946750D03*
X46565Y1946703D03*
X44368Y1951450D03*
X45999Y1971450D03*
X28799Y1919060D03*
X14999Y1940050D03*
X79500Y1987500D03*
X61500D03*
X44500Y1987000D03*
X26500D03*
X55999Y1982550D03*
X157299Y5150D03*
X107000Y6000D03*
X169300Y130300D03*
X178700Y129900D03*
X152999Y141050D03*
X123499Y149050D03*
X133999D03*
X142999Y141050D03*
X132999Y141550D03*
X176499Y140050D03*
X167499Y149550D03*
X144499Y149050D03*
X163499Y140050D03*
X160999Y149550D03*
X123499Y140050D03*
X112999Y124050D03*
X111790Y132259D03*
X152499Y149550D03*
X173499Y149050D03*
X175999Y82428D03*
X127999Y157050D03*
X177899Y199250D03*
X117500Y162300D03*
X124300Y167800D03*
X131799Y201950D03*
X142688Y218861D03*
X143110Y203861D03*
X114900Y177900D03*
X135399Y277050D03*
X130799Y300250D03*
X147099Y245350D03*
X124999Y246050D03*
X123300Y256000D03*
X158999Y259800D03*
X152808Y246341D03*
X166800Y240800D03*
X133000Y240500D03*
X157740Y273924D03*
X157440Y283924D03*
Y303924D03*
Y313924D03*
X139399Y372350D03*
X167299Y369350D03*
X130099Y326150D03*
X134699Y356050D03*
X126099Y396150D03*
X152499Y395950D03*
X99399Y437450D03*
X124899Y409050D03*
X133499Y445050D03*
X166500Y428500D03*
X153459Y427494D03*
X128999Y445550D03*
X130000Y452000D03*
X154101Y445550D03*
X102100Y514900D03*
X163449Y521650D03*
X108599Y557236D03*
X154099Y529236D03*
X107526Y528996D03*
X104502Y530552D03*
X138999Y524213D03*
X101500Y536500D03*
X173100Y483100D03*
X139200Y484300D03*
X134499Y488050D03*
X168453Y527949D03*
X160932Y549468D03*
X161000Y639100D03*
X108900Y587600D03*
X162500Y623400D03*
X140000Y587700D03*
X140499Y600550D03*
X124999Y643050D03*
X129000Y636600D03*
X128600Y640500D03*
X140900Y644000D03*
X134300Y646400D03*
X152400Y643300D03*
X140499Y626050D03*
X143999Y605550D03*
X170799Y689150D03*
X171999Y672450D03*
X131099Y700450D03*
X139099Y707150D03*
X140400Y649800D03*
X152124Y651868D03*
X159054Y665400D03*
X158885Y679436D03*
Y689436D03*
X141500Y711000D03*
X158385Y719436D03*
X110800Y772700D03*
X178899Y765250D03*
X172599Y774250D03*
X111299Y821050D03*
X172099Y877450D03*
X168499Y846713D03*
X173899Y846550D03*
X161999Y843550D03*
Y848050D03*
X156499Y846050D03*
X156999Y850050D03*
X158114Y883290D03*
X156499Y886950D03*
X172660Y815731D03*
X174199Y841050D03*
X159500Y814700D03*
X109500Y901100D03*
X153299Y943750D03*
X106500Y943000D03*
X105300Y960300D03*
X169299Y956350D03*
X106749Y934367D03*
X108441Y924705D03*
X160399Y922850D03*
X120100Y1053200D03*
X171499Y998650D03*
X156499Y985950D03*
X149499Y997650D03*
X162499Y1023550D03*
X163499Y1035050D03*
X124100Y1047100D03*
X158300Y1015000D03*
X141234Y1029885D03*
X140864Y1044885D03*
X159499Y1044579D03*
X165600Y1057428D03*
X137900Y1103400D03*
X139100Y1097100D03*
X137100Y1084800D03*
X140800Y1076300D03*
X121500Y1083600D03*
X121100Y1075300D03*
X169299Y1067150D03*
X168099Y1083550D03*
X167999Y1092850D03*
X143200Y1116300D03*
X134500Y1108100D03*
X171599Y1139950D03*
X167499Y1118550D03*
X167999Y1130550D03*
X133200Y1132100D03*
X164999Y1075550D03*
X159055Y1070400D03*
X116249Y1102550D03*
X112999Y1103740D03*
X117499Y1079300D03*
X157700Y1114948D03*
X157600Y1124948D03*
X159000Y1083000D03*
X106999Y1114960D03*
X127000Y1113500D03*
X145900Y1163200D03*
X163499Y1171650D03*
X151699Y1158550D03*
X144399Y1171150D03*
X150999Y1181150D03*
X141499Y1185550D03*
X151499Y1173050D03*
X121657Y1224604D03*
X120999Y1188050D03*
X111999D03*
X102999D03*
X114999Y1210363D03*
X130699Y1210653D03*
X118999Y1219050D03*
X128400Y1188600D03*
X104999Y1231050D03*
X100999Y1231032D03*
X120999Y1228550D03*
X120499Y1264550D03*
X126499D03*
X123938Y1267623D03*
X103499Y1305050D03*
X117149Y1267550D03*
X101500Y1352000D03*
X113500D03*
X113000Y1341000D03*
X102000D03*
X145999Y1353050D03*
X167499Y1389050D03*
X107228Y1330552D03*
X107500Y1340500D03*
X110499Y1365050D03*
X109999Y1355050D03*
X138000Y1359025D03*
X111499Y1311800D03*
X125999Y1315550D03*
X132999Y1319550D03*
X142667Y1319218D03*
X149562Y1315987D03*
X133475Y1331200D03*
X156999Y1397750D03*
X143199Y1412050D03*
X163499Y1433350D03*
X166799Y1409350D03*
X178200Y1393400D03*
X176599Y1447450D03*
X172299Y1465850D03*
X139815Y1454438D03*
X139235Y1460973D03*
X123999Y1473050D03*
X127898Y1462441D03*
X107300Y1438100D03*
X114499Y1432050D03*
X114000Y1425400D03*
X107999Y1448050D03*
X165499Y1453550D03*
X157915Y1420460D03*
X140799Y1435460D03*
X150338Y1453958D03*
X152499Y1462940D03*
X105099Y1459150D03*
X166799Y1487450D03*
X176299Y1500150D03*
X157440Y1490460D03*
X159054Y1476200D03*
X157440Y1500460D03*
Y1520460D03*
Y1530460D03*
X100499Y1479650D03*
X122199Y1476050D03*
X124999Y1616050D03*
Y1620050D03*
Y1629050D03*
Y1633050D03*
X119999Y1629050D03*
X120100Y1633100D03*
X122499Y1668550D03*
Y1672550D03*
X104999Y1708963D03*
X126562Y1670613D03*
X118999Y1670550D03*
X141500Y1715500D03*
X117249Y1712090D03*
X165575Y1676975D03*
X157500Y1797400D03*
X126599Y1789650D03*
X120299Y1796150D03*
X142144Y1801644D03*
X107300Y1746300D03*
X107100Y1736000D03*
X104417Y1791480D03*
X97999Y1815050D03*
X104500Y1813400D03*
X173899Y1813250D03*
X177599Y1866750D03*
X168299Y1879850D03*
X168499Y1855550D03*
X127499Y1889050D03*
X126999Y1882550D03*
X111499Y1877550D03*
Y1882550D03*
X122999Y1883050D03*
X115999Y1882550D03*
X135999Y1881550D03*
X141300Y1866400D03*
X141800Y1860500D03*
X157999Y1840972D03*
X158000Y1825400D03*
X159054Y1881800D03*
X167200Y1868000D03*
X159054Y1855050D03*
X143491Y1856400D03*
X116499Y1877550D03*
X122999Y1889050D03*
X168899Y1960750D03*
X163599Y1892050D03*
X159173Y1935972D03*
X142499Y1905972D03*
X141499Y1895972D03*
X159421Y1925972D03*
X98000Y1987500D03*
X163500D03*
X146000D03*
X128500D03*
X115000Y1987000D03*
X246200Y65800D03*
X246000Y61300D03*
Y56500D03*
Y52100D03*
X245600Y43800D03*
X245500Y39100D03*
X247100Y47900D03*
X189499Y4550D03*
X206999Y5050D03*
X226499D03*
X241999D03*
X261499Y4550D03*
X246000Y70800D03*
X244900Y149100D03*
X244499Y136550D03*
Y122050D03*
X201499Y104550D03*
X245499Y100550D03*
X246499Y86050D03*
Y80550D03*
X229099Y161350D03*
X206899Y171650D03*
X190199Y178650D03*
X197899Y165075D03*
X249800Y248800D03*
X235399Y263350D03*
X201199Y266750D03*
X181299Y267350D03*
X213499Y283864D03*
X187199Y359050D03*
X223799Y365350D03*
X209199Y365050D03*
X181599Y396250D03*
X217599Y396450D03*
X258999Y396650D03*
X213400Y355300D03*
X224998Y357049D03*
X233998Y357549D03*
X239400Y357400D03*
X252935Y319114D03*
X214063Y318114D03*
X231800Y318414D03*
X179700Y425800D03*
X209999Y426150D03*
X237699Y426050D03*
X218499Y474850D03*
X244199Y483350D03*
X224299Y494650D03*
X242099Y511750D03*
X182499Y532550D03*
X244999Y559550D03*
Y545050D03*
X220499Y560050D03*
Y545550D03*
X257499Y530050D03*
Y512550D03*
Y498050D03*
X205300Y508100D03*
X190499Y507513D03*
X257199Y640050D03*
X224999Y613450D03*
X256499Y609050D03*
Y591550D03*
Y577050D03*
X245000Y647000D03*
X244499Y632050D03*
X219999Y647050D03*
Y632550D03*
X207300Y639400D03*
X206499Y623550D03*
Y609050D03*
X181999Y641550D03*
Y624050D03*
Y609550D03*
X244999Y577050D03*
X220499Y577550D03*
X193549Y575875D03*
X199199Y659150D03*
X234200Y668300D03*
X226399Y677550D03*
X212999Y677350D03*
X190399Y689050D03*
X182599Y688350D03*
X246500Y663300D03*
X218800Y668700D03*
X216999Y686550D03*
X213999Y725050D03*
X230849Y726050D03*
X252499D03*
X224099Y770250D03*
X209500Y759000D03*
X208799Y766750D03*
X214799Y774750D03*
X245599Y773450D03*
X234299Y773750D03*
X247099Y795050D03*
X227199D03*
X197099D03*
X254699Y807650D03*
X233799Y806350D03*
X208299Y805350D03*
X198199Y805950D03*
X190699Y778350D03*
X228999Y765550D03*
X218224Y765325D03*
X241600Y765700D03*
X236800Y765800D03*
X244099Y857450D03*
X245199Y878050D03*
X232399Y886550D03*
X252899Y886350D03*
X252399Y838250D03*
X245399Y823550D03*
X217300Y816800D03*
X199000Y815000D03*
X200539Y890300D03*
X198499Y884113D03*
X245399Y907450D03*
X243899Y923650D03*
X242199Y938750D03*
X256199Y916250D03*
X254899Y929250D03*
X253499Y938050D03*
X252499Y948850D03*
X244199Y973250D03*
X225299Y957650D03*
X213999Y958650D03*
X206699Y953050D03*
X203999Y943350D03*
X204699Y929450D03*
X205999Y978250D03*
X256499Y967050D03*
X233499Y966050D03*
X216999Y967550D03*
X198924Y975975D03*
X229562Y904113D03*
X215499Y905550D03*
X254499Y984550D03*
X245899Y995250D03*
X232299Y981950D03*
X206299Y990250D03*
X207299Y1008150D03*
X202100Y1028100D03*
X253999Y1052050D03*
X253499Y1038550D03*
X232499Y1038050D03*
X216499Y1053050D03*
X215999Y1039550D03*
X258999Y1011550D03*
X233999Y1012550D03*
Y997050D03*
X217999Y1012050D03*
X217499Y998550D03*
Y981050D03*
X199499Y1093850D03*
X209900Y1093600D03*
X249499Y1104150D03*
X260349Y1139200D03*
X256000Y1133000D03*
X255000Y1125700D03*
X221300Y1083238D03*
X214499Y1154250D03*
X223099Y1182750D03*
X210199Y1173450D03*
X204199Y1163850D03*
X208199Y1145850D03*
X180400Y1202800D03*
X201600Y1205900D03*
X220999Y1224350D03*
X242199Y1210050D03*
X242599Y1198350D03*
X232599Y1195750D03*
X247899Y1208650D03*
X251999Y1184550D03*
X212499Y1212550D03*
X181700Y1219900D03*
X212499Y1184550D03*
X196499Y1224550D03*
Y1215550D03*
Y1196550D03*
X202199Y1276850D03*
X202899Y1291450D03*
X179500Y1262000D03*
X179800Y1244100D03*
X196399Y1236650D03*
X221599Y1237250D03*
X222299Y1251850D03*
X229899Y1250550D03*
X216300Y1274800D03*
X234299Y1232650D03*
X261199Y1227950D03*
X250900Y1248500D03*
X242900Y1263000D03*
X232799Y1276150D03*
X254899Y1289950D03*
X241399Y1303250D03*
X211499Y1267050D03*
Y1258050D03*
Y1239050D03*
X195499Y1279050D03*
Y1270050D03*
Y1251050D03*
X239099Y1314150D03*
X252399Y1326350D03*
X219099Y1325950D03*
X226599Y1340250D03*
X207699Y1337950D03*
X195500Y1352500D03*
X213199Y1350050D03*
X227399Y1363050D03*
X234300Y1375700D03*
X217499Y1387450D03*
X249800Y1388400D03*
X245999Y1358050D03*
X246499Y1370050D03*
X245999Y1339050D03*
X208049Y1385550D03*
X258999Y1396950D03*
X230599Y1400250D03*
X217999Y1408850D03*
X204699Y1418350D03*
X203199Y1393250D03*
X201000Y1408500D03*
X180599Y1424050D03*
X180000Y1439500D03*
X204999Y1472650D03*
X250199Y1473550D03*
X226300Y1447800D03*
X230899Y1437350D03*
X238899Y1453750D03*
X259299Y1438750D03*
X227999Y1421550D03*
X212400Y1433700D03*
X194200Y1457900D03*
X244999Y1412550D03*
X245499Y1424550D03*
X181500Y1479000D03*
X202399Y1500750D03*
X208999Y1491250D03*
X247500Y1499000D03*
X248000Y1482000D03*
X212899Y1535550D03*
X230999D03*
X213399Y1500300D03*
X236999Y1535550D03*
X232650Y1493450D03*
X246200Y1617600D03*
X239400Y1624300D03*
X218000Y1614300D03*
X209200Y1624000D03*
X228999Y1637550D03*
X211999Y1568550D03*
X238300Y1575100D03*
X231499Y1575050D03*
X224499D03*
X217999Y1574550D03*
X211999D03*
X258700Y1645100D03*
X237400Y1663800D03*
X230600Y1670500D03*
X197600Y1694900D03*
X204400Y1688200D03*
X216601Y1684350D03*
X226800Y1684200D03*
X220100Y1691700D03*
X209901Y1691850D03*
X212000Y1701300D03*
X201801Y1701450D03*
X195001Y1708150D03*
X205200Y1708000D03*
X180701Y1716050D03*
X195500Y1717000D03*
X200600Y1663600D03*
X199900Y1670600D03*
X213000Y1672500D03*
X181900Y1675300D03*
X255699Y1722550D03*
X222700Y1710100D03*
X242999Y1658050D03*
X193499Y1674050D03*
X253999Y1676550D03*
X235499Y1697050D03*
X256499Y1710050D03*
X179999Y1655887D03*
X186000Y1644000D03*
X180000Y1731000D03*
X179701Y1724550D03*
X195000Y1725500D03*
X249199Y1743150D03*
X222499Y1743850D03*
X259499Y1760650D03*
X221499Y1760950D03*
X199699Y1761450D03*
X220799Y1791550D03*
X252199Y1793050D03*
X238699Y1801850D03*
X205199Y1801950D03*
X182299Y1801350D03*
X206900Y1726700D03*
X185999Y1746050D03*
X237999Y1730550D03*
X244999Y1755050D03*
X194049Y1792600D03*
X253899Y1813250D03*
X215299Y1813950D03*
X255999Y1855950D03*
X204399Y1855450D03*
X206999Y1867550D03*
X241199Y1867150D03*
X244700Y1878700D03*
X224800Y1867000D03*
X212399Y1885850D03*
X199599Y1879850D03*
X181099Y1885850D03*
X261499Y1825050D03*
X209999D03*
X192100Y1813500D03*
X228999Y1856050D03*
X236225Y1883125D03*
X241255Y1896055D03*
X205499Y1968650D03*
X183999Y1968150D03*
X190399Y1961250D03*
X207199Y1892850D03*
X191599Y1891550D03*
X238999Y1970550D03*
X232999Y1971050D03*
X227499D03*
X232314Y1890513D03*
X221300Y1971200D03*
X213562Y1926113D03*
X220062Y1931113D03*
X240964Y1934113D03*
X240900Y1979000D03*
X225199Y1978750D03*
X209699D03*
X188199Y1978250D03*
X254500Y1987500D03*
X236500D03*
X216999Y1987550D03*
X199000Y1987500D03*
X183000D03*
X199600Y1974900D03*
X278999Y5050D03*
X292999Y4550D03*
X310499Y5050D03*
X329999D03*
X343499Y60150D03*
X306999Y55450D03*
X311299D03*
X315799Y55350D03*
X296099Y17100D03*
X305099Y17000D03*
X311400Y17100D03*
X317000Y17300D03*
X306100Y126500D03*
X332200Y94200D03*
X283599Y106250D03*
X274700Y131500D03*
X280999Y120050D03*
X291999Y94050D03*
X343799Y204550D03*
X321799Y173950D03*
X343399Y161350D03*
X307199Y205550D03*
X317499Y192950D03*
X331499Y193250D03*
X262699Y208550D03*
X262299Y164050D03*
X280999Y152050D03*
X325499Y249450D03*
X313199Y270350D03*
X313000Y313900D03*
X316999Y312576D03*
X276299Y376050D03*
X299899Y376650D03*
X328799Y372350D03*
X339399Y358050D03*
X289399Y395750D03*
X310999Y396250D03*
X338399Y395650D03*
X313039Y352350D03*
X321900Y364600D03*
X321748Y343299D03*
X298800Y333000D03*
X294500Y339000D03*
X277799Y338599D03*
X266699Y425050D03*
X336099Y417550D03*
X322099Y426850D03*
X338899Y433850D03*
X300899Y431850D03*
X328599Y442250D03*
X291599Y446150D03*
X266199Y472350D03*
X277999Y545350D03*
X329999Y510450D03*
X298599Y501250D03*
X309399Y513450D03*
X321999Y533150D03*
X297599Y519350D03*
X340799Y512050D03*
X341399Y535850D03*
Y558950D03*
X331999Y555050D03*
Y540550D03*
X307499Y555550D03*
Y541050D03*
X281999Y529550D03*
Y512050D03*
Y497550D03*
X321999Y550550D03*
X297499Y551050D03*
X321299Y565250D03*
X296199Y568550D03*
X320799Y582050D03*
X340299Y586550D03*
X342199Y613050D03*
X328599Y602450D03*
X302899Y607950D03*
X328499Y635650D03*
X317999Y627850D03*
X342099Y646350D03*
X280999Y608550D03*
Y591050D03*
Y576550D03*
X331999Y572550D03*
X307499Y573050D03*
X331999Y646550D03*
X307499Y647050D03*
X293999Y630550D03*
Y616050D03*
X269499Y631050D03*
Y616550D03*
X341899Y664950D03*
X342599Y678850D03*
X341399Y715050D03*
X330799Y712450D03*
X324599Y696150D03*
X297699Y681850D03*
X296399Y716950D03*
X308899Y705150D03*
X298399Y703450D03*
X331999Y678550D03*
Y661050D03*
X307499Y679050D03*
Y661550D03*
X293999Y648050D03*
X269499Y648550D03*
X308999Y716450D03*
X315999Y718950D03*
X338099Y811650D03*
X307999Y803150D03*
X307899Y794550D03*
X287799Y794850D03*
X268099Y795450D03*
X275299Y806350D03*
X292999Y743650D03*
X298000Y743500D03*
X323249Y749010D03*
X324959Y766750D03*
X277039Y740300D03*
X315000Y754500D03*
X338599Y821650D03*
X318999Y814350D03*
X338599Y840450D03*
X325599Y823950D03*
X283599Y857450D03*
X293899Y843850D03*
X304899Y856150D03*
X315199Y869450D03*
X323099Y885050D03*
X340099Y887350D03*
X330299Y871850D03*
X323799Y859850D03*
X313499Y847850D03*
X300199Y835250D03*
X288899Y820550D03*
X264999Y858450D03*
X280999Y843050D03*
Y827550D03*
X264999Y842550D03*
X264499Y829050D03*
X297499Y884050D03*
Y868550D03*
X281499Y883550D03*
X280999Y870050D03*
X265799Y901850D03*
X274299Y912950D03*
X310699Y943550D03*
X323499Y956950D03*
X329799Y970650D03*
X331099Y923650D03*
X322099Y913650D03*
X302499Y899050D03*
X321099Y899650D03*
X338399Y901050D03*
X340099Y910350D03*
X340399Y931250D03*
X340099Y952850D03*
X328099Y937250D03*
X315199Y925950D03*
X302199Y914650D03*
X287299Y901050D03*
X269599Y923950D03*
X267199Y935350D03*
X264799Y946850D03*
X263299Y959350D03*
X281099Y943550D03*
X278799Y956150D03*
X277599Y975250D03*
X290099Y948650D03*
X289399Y963350D03*
X288099Y971250D03*
X299399Y965950D03*
X298099Y977250D03*
X307999Y970650D03*
X272999Y965550D03*
X333099Y983450D03*
X285399Y982950D03*
X294699Y989550D03*
X306699Y981250D03*
X304399Y997550D03*
X320999Y997250D03*
X331299Y1017150D03*
X331599Y1028750D03*
X329599Y1040750D03*
X321299Y1012450D03*
Y1024750D03*
X318299Y1038750D03*
X329599Y1057050D03*
X317699Y1054650D03*
X299999Y1052350D03*
X289699Y1021750D03*
X298399Y1008150D03*
X287099Y1000150D03*
X306399Y1020750D03*
X303699Y1038050D03*
X304699Y1057050D03*
X287099Y1035050D03*
X275099Y1024750D03*
X262499Y995850D03*
X269999Y1052550D03*
Y1037050D03*
X274999Y1012050D03*
Y996550D03*
X272999Y981050D03*
X339599Y1081550D03*
X319999Y1066950D03*
X274900Y1115600D03*
X262499Y1129150D03*
X272999Y1102850D03*
X312299Y1093550D03*
X276299Y1134550D03*
X290699Y1122650D03*
X329299Y1098550D03*
X326599Y1112350D03*
X307999Y1142050D03*
X299499Y1113550D03*
Y1098050D03*
X283499Y1113050D03*
X282999Y1099550D03*
X332999Y1138550D03*
Y1123050D03*
X317999Y1137550D03*
X316499Y1124550D03*
X283299Y1144850D03*
X323999Y1153250D03*
X304499Y1156650D03*
X313499Y1170150D03*
X291399Y1174150D03*
X300699Y1185150D03*
X279799Y1191750D03*
X286599Y1203750D03*
X315408Y1202663D03*
X329799Y1182750D03*
X311999Y1213850D03*
X300699Y1227350D03*
X272999Y1214150D03*
X326649Y1218850D03*
X328999Y1200550D03*
X333349Y1307000D03*
X310299Y1240050D03*
X264800Y1261300D03*
X283799Y1249250D03*
X304699Y1265850D03*
X312499Y1280350D03*
X300499Y1305350D03*
X274299Y1276450D03*
X295399Y1292950D03*
X281099Y1302850D03*
X333349Y1288900D03*
Y1270500D03*
X327999Y1255050D03*
X326649Y1227850D03*
X333349Y1332800D03*
X311500Y1316300D03*
X264799Y1313850D03*
X286799Y1326450D03*
X297899Y1336150D03*
X298099Y1357250D03*
X265299Y1339650D03*
X263699Y1359550D03*
X301699Y1377950D03*
X278799Y1386250D03*
X265499Y1376950D03*
X343599Y1360050D03*
X344399Y1338150D03*
X313600Y1391300D03*
X312900Y1366900D03*
X333349Y1363500D03*
X311900Y1344900D03*
X286499Y1364050D03*
Y1345050D03*
X301699Y1395750D03*
X268499Y1453550D03*
X278000Y1422000D03*
X270599Y1408550D03*
X303499Y1411250D03*
X300899Y1433350D03*
X286600Y1449700D03*
X304699Y1457550D03*
X344099Y1449550D03*
Y1421150D03*
Y1393750D03*
X313600Y1442700D03*
X312800Y1467400D03*
X333349Y1429500D03*
X312100Y1420700D03*
X285499Y1418550D03*
Y1427550D03*
Y1399550D03*
X333349Y1393100D03*
Y1481900D03*
X332500Y1519700D03*
X296599Y1497150D03*
X312000Y1514600D03*
X286700Y1516100D03*
X289999Y1554650D03*
X293700Y1553351D03*
X276039Y1551300D03*
X314999Y1527550D03*
X307000Y1619600D03*
X297800Y1561600D03*
X291400Y1561500D03*
X344500Y1583600D03*
X337199Y1636350D03*
X278499Y1621550D03*
X265700Y1635100D03*
X324000Y1562500D03*
X312999Y1566050D03*
X323999Y1577250D03*
X289000Y1641800D03*
X320299Y1642950D03*
X316799Y1657450D03*
X302399Y1662950D03*
X284300Y1676900D03*
X334399Y1691650D03*
X329999Y1716950D03*
X291099Y1707450D03*
X335767Y1662735D03*
X318499Y1675550D03*
X299999Y1696050D03*
X270999Y1660550D03*
X273499Y1694050D03*
X280499Y1718550D03*
X320999Y1706050D03*
X303999Y1722050D03*
X343899Y1752650D03*
X297099Y1733850D03*
X270599Y1748950D03*
X290699Y1760750D03*
X286599Y1791850D03*
X327299D03*
X322299Y1802150D03*
X303999Y1800850D03*
X270599Y1801450D03*
X263499Y1734550D03*
X285499Y1742550D03*
X321999Y1733050D03*
X303499Y1753550D03*
X321499Y1772550D03*
X315499Y1812250D03*
X284299Y1811150D03*
X270299Y1867250D03*
X337499Y1855950D03*
X316999D03*
X298999D03*
X308099Y1880550D03*
X295299Y1870250D03*
X313599Y1889250D03*
Y1870250D03*
X326399Y1876250D03*
X336799Y1888950D03*
Y1869950D03*
X283999Y1856050D03*
X314099Y1901250D03*
X326899Y1907250D03*
X326399Y1895250D03*
X335799Y1916450D03*
X336799Y1897950D03*
X305999Y1913050D03*
X302499Y1922050D03*
X280689Y1942710D03*
X296858Y1956228D03*
X315999Y1958550D03*
X327100Y1966472D03*
X329999Y1952273D03*
X325221Y1927272D03*
X313499Y1919050D03*
X326799Y1977050D03*
X329999Y1987550D03*
X311500Y1987500D03*
X291499Y1987550D03*
X272000Y1987500D03*
X416999Y25050D03*
X417499Y46550D03*
X416999Y63550D03*
X345499Y5050D03*
X364999Y4550D03*
X382499Y5050D03*
X395999Y5550D03*
X413499Y6050D03*
X398799Y36152D03*
X381999Y50150D03*
X386799Y45000D03*
X426000Y93500D03*
X381299Y136750D03*
X389599Y90950D03*
X400499Y134050D03*
Y119550D03*
X363999Y136050D03*
X417499Y79050D03*
Y93550D03*
Y108050D03*
Y125550D03*
X416999Y145050D03*
X357503Y77043D03*
X374499Y77550D03*
X385999Y78050D03*
X401499Y80550D03*
X387599Y220150D03*
X385999Y207250D03*
X354099Y175350D03*
X389299Y161650D03*
X400499Y151550D03*
X363999Y153550D03*
X416999Y164050D03*
X417999Y185050D03*
X423799Y259750D03*
X383299Y310250D03*
X386899Y299250D03*
X359399Y307250D03*
X347399Y301950D03*
X355999Y242750D03*
X347699Y269050D03*
X382999Y276650D03*
X412999Y307550D03*
Y290050D03*
Y275550D03*
X354099Y373050D03*
X368299Y386350D03*
X357999Y359050D03*
X380599Y381050D03*
X386599Y348450D03*
X394899Y357750D03*
X422499Y348150D03*
X422199Y363350D03*
X420199Y391350D03*
X419599Y458550D03*
X426599Y415350D03*
X415099Y422550D03*
X410799Y431150D03*
X354699Y426650D03*
X356399Y451750D03*
X351399Y470750D03*
X358399Y498650D03*
X357399Y521250D03*
Y530550D03*
Y543850D03*
X357999Y559450D03*
X420199Y638550D03*
X427499Y624550D03*
X359399Y576050D03*
Y599650D03*
X360399Y615550D03*
X359699Y627550D03*
X345399Y698950D03*
X358899Y657150D03*
X359399Y669450D03*
X359199Y690650D03*
X357699Y707750D03*
X353999Y787750D03*
X347699Y773450D03*
X355999Y752850D03*
X424999Y766550D03*
X422999Y785050D03*
Y799550D03*
X418799Y896050D03*
Y877050D03*
X422499Y855550D03*
Y836550D03*
X422999Y817050D03*
X374500Y973500D03*
X375000Y939000D03*
Y1034000D03*
X424299Y1034050D03*
X423299Y1013050D03*
Y994050D03*
X373500Y1089500D03*
X419999Y1115550D03*
X409499Y1102550D03*
X416099Y1183550D03*
X415499Y1176050D03*
Y1161550D03*
X419499Y1219550D03*
X377499Y1210050D03*
Y1201050D03*
Y1182050D03*
X420099Y1241550D03*
X419499Y1234050D03*
X376599Y1293950D03*
X376499Y1264550D03*
Y1255550D03*
Y1236550D03*
X424999Y1278550D03*
X425499Y1290550D03*
X424999Y1259550D03*
X416699Y1342650D03*
X416199Y1367550D03*
X375599Y1323350D03*
X374499Y1375550D03*
Y1366550D03*
Y1347550D03*
X423299Y1430350D03*
X426799Y1416050D03*
X422299Y1394950D03*
X425799Y1447950D03*
X427099Y1469150D03*
X376299Y1437650D03*
X373099Y1456550D03*
X373499Y1430050D03*
Y1421050D03*
Y1402050D03*
X414799Y1532350D03*
X424299Y1541350D03*
X374099Y1554550D03*
X374799Y1491250D03*
X415999Y1603250D03*
X416199Y1625250D03*
X425499Y1635050D03*
X418299Y1561250D03*
X351899Y1570850D03*
X350600Y1610900D03*
X349099Y1634550D03*
X376099Y1572850D03*
X375099Y1608250D03*
X377700Y1629000D03*
X414799Y1653750D03*
X414399Y1678350D03*
X414499Y1707250D03*
X374999Y1656750D03*
X377099Y1696350D03*
X380099Y1709650D03*
X351099Y1691150D03*
X352000Y1700400D03*
X427499Y1662050D03*
X417799Y1790850D03*
X387899Y1802850D03*
X359499Y1736850D03*
X376799Y1734050D03*
X393499Y1759550D03*
X376499Y1775550D03*
X357999Y1796050D03*
X410757Y1772872D03*
X393999Y1784550D03*
X422999Y1778550D03*
X367000Y1810000D03*
X414499Y1810450D03*
X355699Y1810750D03*
X426499Y1855450D03*
X406999Y1855950D03*
X391499D03*
X369499D03*
X351999Y1855450D03*
X359999Y1878550D03*
X421399Y1888050D03*
X369799Y1880050D03*
X389499Y1885050D03*
X348999Y1879050D03*
X406499Y1874050D03*
X360000Y1967500D03*
X367299Y1956950D03*
X358999Y1925050D03*
X359999Y1897550D03*
Y1906550D03*
X420399Y1962550D03*
Y1934550D03*
Y1953550D03*
X421399Y1916050D03*
Y1907050D03*
X347699Y1972250D03*
X367999Y1940250D03*
X369199Y1919750D03*
X369999Y1901950D03*
X388499Y1959550D03*
Y1950550D03*
Y1932950D03*
X389499Y1913050D03*
Y1904050D03*
X349499Y1910050D03*
X348499Y1956550D03*
X347999Y1944550D03*
Y1925550D03*
X348999Y1898050D03*
X406999Y1905050D03*
X405999Y1951550D03*
X405499Y1939550D03*
Y1920550D03*
X406499Y1893050D03*
X385099Y1975950D03*
X420799Y1977250D03*
X399299Y1976750D03*
X367299Y1972950D03*
X420500Y1987000D03*
X403500D03*
X364999Y1987050D03*
X382499Y1987550D03*
X345499D03*
X436499Y50350D03*
Y31350D03*
X466799Y64750D03*
X465799Y43750D03*
Y24750D03*
X499999Y64050D03*
X500499Y47050D03*
X499999Y25550D03*
X432999Y6050D03*
X448499D03*
X467999Y5550D03*
X485499Y6050D03*
X498999D03*
X437499Y71350D03*
X442799Y142450D03*
X441799Y121450D03*
Y102450D03*
X471399Y124550D03*
X470399Y103550D03*
Y84550D03*
X473099Y141050D03*
X499999Y145550D03*
X500499Y126050D03*
Y108550D03*
Y79550D03*
Y94050D03*
X502899Y217150D03*
X504199Y193250D03*
X472999Y214550D03*
X483599Y179350D03*
X446799Y205650D03*
X445799Y184650D03*
Y165650D03*
X474099Y181050D03*
X473099Y160050D03*
X449999Y217050D03*
X430499D03*
X499999Y164550D03*
X466399Y304950D03*
X479299Y297250D03*
X437499Y307050D03*
Y289550D03*
Y275050D03*
X498399Y470050D03*
X503699Y419250D03*
X472499Y458050D03*
X468799Y414250D03*
X443199Y440850D03*
X440099Y459250D03*
X431099Y479350D03*
X450300Y404200D03*
X490499Y464050D03*
X490999Y444550D03*
Y427050D03*
Y412550D03*
X454499Y472550D03*
X454999Y438550D03*
X454499Y458050D03*
X453999Y417550D03*
X430099Y551450D03*
X485299Y534550D03*
X508699Y498950D03*
X471499Y493950D03*
X452499Y565050D03*
X491499Y504050D03*
X490499Y483050D03*
X453999Y509550D03*
X454499Y490050D03*
X504499Y598050D03*
Y580550D03*
Y566050D03*
X479999Y598550D03*
Y581050D03*
Y566550D03*
X509999Y640550D03*
X452499Y597050D03*
Y579550D03*
X427999Y597550D03*
Y580050D03*
Y565550D03*
X506599Y711650D03*
X487299Y716950D03*
X451099Y711650D03*
X450399Y672750D03*
X444799Y687350D03*
X509999Y672550D03*
Y655050D03*
X488499Y691050D03*
Y673550D03*
Y659050D03*
X463999Y691550D03*
Y674050D03*
Y659550D03*
X467699Y772750D03*
X468699Y788350D03*
X472999Y736550D03*
X489599Y752450D03*
X490299Y734550D03*
X453399Y807950D03*
X452099Y781450D03*
Y762450D03*
X435299Y795150D03*
Y777650D03*
Y763150D03*
X437299Y744650D03*
X495999Y795050D03*
X475699Y880450D03*
X479599Y847550D03*
X462999Y884050D03*
Y865050D03*
X453399Y826950D03*
X434799Y833650D03*
Y814650D03*
X464499Y896050D03*
X493499Y884050D03*
Y865050D03*
X493999Y845550D03*
Y813550D03*
Y828050D03*
X506899Y919950D03*
Y900950D03*
X443599Y945650D03*
X442599Y924650D03*
Y905650D03*
X486799Y941050D03*
X485799Y920050D03*
Y901050D03*
X461999Y966050D03*
X462499Y946550D03*
Y914550D03*
Y929050D03*
X494099Y1017350D03*
X493099Y996350D03*
X462499Y1043850D03*
X461999Y985050D03*
X474499Y1115050D03*
X491999Y1115550D03*
X454999D03*
X439499D03*
X501499Y1102550D03*
X463999Y1102050D03*
X481499Y1102550D03*
X444499D03*
X428999D03*
X436999Y1142550D03*
Y1128050D03*
X504399Y1132250D03*
X473099Y1144550D03*
X453499Y1140550D03*
X484499Y1085850D03*
X483499Y1064850D03*
X433599Y1085550D03*
X432599Y1064550D03*
X463499Y1083850D03*
X462499Y1062850D03*
X437599Y1150050D03*
X487099Y1218050D03*
X486499Y1210550D03*
Y1196050D03*
X443199Y1224250D03*
X507199Y1224350D03*
X506599Y1202350D03*
Y1216850D03*
X505399Y1153250D03*
X474099Y1165550D03*
X454499Y1161550D03*
X443799Y1274250D03*
Y1246250D03*
Y1265250D03*
X443199Y1238750D03*
X507199Y1252350D03*
Y1243350D03*
X465499Y1284550D03*
Y1293550D03*
Y1265550D03*
X498299Y1323350D03*
X468999Y1323950D03*
X428499Y1325350D03*
X508599Y1370550D03*
X444899Y1377950D03*
X434499Y1360250D03*
X448099Y1341250D03*
X473999Y1342450D03*
X485599Y1367550D03*
X468699Y1362850D03*
X466699Y1378150D03*
X498899Y1386450D03*
X499199Y1350550D03*
X459699Y1468050D03*
X464199Y1401450D03*
X459999Y1424050D03*
X498899Y1408350D03*
X500899Y1434350D03*
X505899Y1466250D03*
X482599Y1449950D03*
X456399Y1445950D03*
X445099Y1464250D03*
X478299Y1464850D03*
X481499Y1417050D03*
Y1402550D03*
X441499Y1431550D03*
Y1414050D03*
Y1399550D03*
X499699Y1538950D03*
X466999Y1530650D03*
X488299Y1531050D03*
X461399Y1541650D03*
X474299Y1544750D03*
X452199Y1550650D03*
X444299Y1532650D03*
X439599Y1552150D03*
X465999Y1603450D03*
X487099Y1606250D03*
X449199Y1579050D03*
X443799Y1612250D03*
X460199Y1632850D03*
X484999Y1636550D03*
X501399Y1634550D03*
X508199Y1610450D03*
X510100Y1579800D03*
X472299Y1572050D03*
X502199Y1566250D03*
X472499Y1620550D03*
Y1611550D03*
X484200Y1579900D03*
X432499Y1617550D03*
X434500Y1579500D03*
X431999Y1605550D03*
X435300Y1715300D03*
X448399Y1699450D03*
X447699Y1682850D03*
X449599Y1656950D03*
X483599Y1662550D03*
X485599Y1694850D03*
X502899Y1709650D03*
X507399Y1683350D03*
X509199Y1660550D03*
X468499Y1712550D03*
X467999Y1687050D03*
Y1696050D03*
Y1668050D03*
X432400Y1680100D03*
X428600Y1691200D03*
X436799Y1772550D03*
X472699Y1792150D03*
X429499Y1748050D03*
X458499Y1742050D03*
X441499Y1758050D03*
X480999Y1756050D03*
X463999Y1772050D03*
X445499Y1792550D03*
X508200Y1758200D03*
X484999Y1779050D03*
X496999Y1799550D03*
X481299Y1811150D03*
X448099Y1809450D03*
X499999Y1854950D03*
X480499Y1855450D03*
X464999D03*
X443999Y1855950D03*
X476199Y1877450D03*
X434299Y1876050D03*
X446999Y1880050D03*
X492999Y1878050D03*
X504799Y1967550D03*
Y1939550D03*
Y1958550D03*
X505799Y1921050D03*
Y1912050D03*
Y1893050D03*
X475199Y1951950D03*
Y1923950D03*
Y1942950D03*
X476199Y1905450D03*
Y1896450D03*
X459299Y1966850D03*
Y1938850D03*
Y1957850D03*
X460299Y1920350D03*
Y1911350D03*
Y1892350D03*
X433299Y1950550D03*
Y1922550D03*
Y1941550D03*
X434299Y1904050D03*
Y1895050D03*
X445999Y1954550D03*
Y1945550D03*
Y1926550D03*
X446999Y1908050D03*
Y1899050D03*
X493499Y1909050D03*
X492499Y1955550D03*
X491999Y1943550D03*
Y1924550D03*
X492999Y1897050D03*
X509299Y1977250D03*
X493799D03*
X473299D03*
X455799Y1976750D03*
X436299Y1977250D03*
X492500Y1987500D03*
X476000Y1987000D03*
X456500Y1987500D03*
X438999Y1987550D03*
X522899Y64350D03*
Y45350D03*
X587999Y63550D03*
X588499Y46550D03*
X587999Y25050D03*
X541499Y63550D03*
X541999Y46550D03*
X541499Y25050D03*
X516499Y6550D03*
X535999D03*
X551499D03*
X570999Y6050D03*
X588499Y6550D03*
X523899Y85350D03*
X520299Y141450D03*
Y122450D03*
X569099Y112550D03*
X568099Y91550D03*
Y72550D03*
X562799Y146750D03*
Y127750D03*
X587999Y145050D03*
X588499Y125550D03*
X541499Y145050D03*
X541999Y125550D03*
Y108050D03*
Y79050D03*
Y93550D03*
X565999Y199950D03*
X528799D03*
X521299Y162450D03*
X563799Y167750D03*
X587999Y217050D03*
X568499Y217550D03*
X552999D03*
X533499D03*
X588999Y185050D03*
X587999Y164050D03*
X542499Y185050D03*
X541499Y164050D03*
X544799Y293950D03*
X540099Y306550D03*
X516899Y306950D03*
X572999Y287050D03*
X572499Y306550D03*
X572999Y269550D03*
Y255050D03*
X579899Y375750D03*
X573499Y346550D03*
X572499Y325550D03*
X577899Y460550D03*
X578399Y441050D03*
X577399Y420050D03*
X539799Y466050D03*
X538799Y445050D03*
X576099Y481850D03*
X511299Y449150D03*
X519499Y471550D03*
X518999Y416550D03*
X592499Y478050D03*
Y459050D03*
X592999Y439550D03*
Y422050D03*
Y407550D03*
X556499Y467550D03*
X555999Y412550D03*
X539299Y485550D03*
X576599Y522350D03*
X577099Y502850D03*
X518999Y508550D03*
X519499Y489050D03*
X555999Y504550D03*
X556499Y485050D03*
X534499Y640050D03*
X586299Y711250D03*
X565699Y710650D03*
X549999Y710050D03*
X547999Y728550D03*
X573499Y690550D03*
Y673050D03*
Y658550D03*
X534499Y672050D03*
Y654550D03*
Y805950D03*
X511199Y782050D03*
X527499Y747150D03*
X525499Y772450D03*
X547499Y799050D03*
Y780050D03*
X547999Y760550D03*
Y743050D03*
X575499Y802050D03*
X575999Y782550D03*
Y765050D03*
X577999Y732050D03*
X575999Y750550D03*
X526499Y851150D03*
X510899Y868150D03*
X578299Y895650D03*
X541399Y873450D03*
Y854450D03*
X512899Y842550D03*
Y823550D03*
X521999Y895550D03*
X522499Y876050D03*
X576499Y842050D03*
X575499Y821050D03*
X583299Y961450D03*
X578299Y914650D03*
X540299Y956850D03*
X539299Y935850D03*
X570899Y965850D03*
Y946850D03*
X521999Y914550D03*
X562999Y898050D03*
X560499Y968050D03*
X560999Y948550D03*
Y916550D03*
Y931050D03*
X516499Y957050D03*
X514499Y975550D03*
X583299Y980450D03*
X534599Y1048550D03*
X571899Y986850D03*
X573499Y1055550D03*
Y1036550D03*
X541899Y1021450D03*
X540899Y1000450D03*
Y981450D03*
X560499Y987050D03*
X560999Y999050D03*
X558999Y1049550D03*
Y1017550D03*
Y1032050D03*
X513999Y1046050D03*
Y1027050D03*
X514499Y1007550D03*
Y990050D03*
X588499Y1101550D03*
X578999Y1114550D03*
X568499Y1101550D03*
X564499Y1116050D03*
X548999D03*
X529499D03*
X511999Y1115550D03*
X553999Y1103050D03*
X538499D03*
X518999D03*
X535599Y1069550D03*
X574499Y1076550D03*
X558499Y1088050D03*
Y1069050D03*
X547099Y1202750D03*
Y1221750D03*
X546499Y1180750D03*
Y1195250D03*
X567999Y1215550D03*
Y1206550D03*
Y1187550D03*
X527999Y1212550D03*
X527499Y1200550D03*
Y1181550D03*
X579299Y1300750D03*
X527499Y1278150D03*
X530499Y1297050D03*
X561099Y1301050D03*
X566399Y1273850D03*
X549399Y1302850D03*
Y1274850D03*
Y1293850D03*
X548799Y1252850D03*
Y1267350D03*
X547099Y1230750D03*
X583299Y1283250D03*
Y1255250D03*
Y1274250D03*
X582699Y1233250D03*
Y1247750D03*
X565999Y1248550D03*
Y1234050D03*
X525999Y1263050D03*
Y1245550D03*
Y1231050D03*
X555699Y1322950D03*
X581999Y1370150D03*
X559099Y1343250D03*
X545099Y1355250D03*
X518499Y1346950D03*
X540399Y1382150D03*
X523999Y1391050D03*
X523499Y1360050D03*
Y1379050D03*
X580999Y1412750D03*
X575699Y1438950D03*
X538799Y1409750D03*
X536799Y1436350D03*
X528499Y1460250D03*
X546099Y1467550D03*
X582999Y1461250D03*
X557499Y1443050D03*
Y1452050D03*
Y1424050D03*
X516999Y1437050D03*
X517499Y1449050D03*
X516999Y1418050D03*
X590599Y1483450D03*
X529799Y1555050D03*
X567999Y1549950D03*
X582299Y1534150D03*
X538999Y1528350D03*
X518899Y1530150D03*
X532499Y1635550D03*
X552099Y1601950D03*
X553399Y1624550D03*
X590799Y1627850D03*
X588000Y1604000D03*
X588099Y1572050D03*
X552199Y1576650D03*
X569499Y1619550D03*
Y1610550D03*
X573400Y1577600D03*
X529499Y1616550D03*
X533800Y1575500D03*
X528999Y1604550D03*
X518499Y1643950D03*
X538299Y1721050D03*
X532599Y1655650D03*
X554199Y1651950D03*
X555199Y1674750D03*
X555399Y1689350D03*
X555899Y1706750D03*
X580299Y1722550D03*
X590599Y1694450D03*
X580799Y1646150D03*
X572999Y1694550D03*
Y1703550D03*
Y1675550D03*
X532499Y1688550D03*
X532999Y1700550D03*
X532499Y1669550D03*
X582599Y1740050D03*
X560399Y1792550D03*
X555500Y1802700D03*
X539499Y1788150D03*
X526499Y1801150D03*
X556199Y1727050D03*
X522300Y1739200D03*
X532499Y1763050D03*
X515499Y1779050D03*
X531799Y1818450D03*
X514199Y1815750D03*
X591499Y1855950D03*
X573999Y1855450D03*
X554499Y1855950D03*
X538999D03*
X517499Y1855450D03*
X588899Y1882350D03*
X562599Y1874450D03*
X519399Y1876750D03*
X533499Y1884050D03*
X575999Y1888050D03*
X587899Y1956850D03*
Y1928850D03*
Y1947850D03*
X588899Y1910350D03*
Y1901350D03*
X561599Y1948950D03*
Y1920950D03*
Y1939950D03*
X562599Y1902450D03*
Y1893450D03*
X546999Y1966850D03*
Y1938850D03*
Y1957850D03*
X547999Y1920350D03*
Y1911350D03*
Y1892350D03*
X518399Y1951250D03*
Y1923250D03*
Y1942250D03*
X519399Y1904750D03*
Y1895750D03*
X532499Y1958550D03*
Y1949550D03*
Y1930550D03*
X533499Y1912050D03*
Y1903050D03*
X575999Y1907050D03*
X576499Y1919050D03*
X574999Y1953550D03*
X575499Y1965550D03*
X574999Y1934550D03*
X585799Y1976250D03*
X570299D03*
X546299Y1977250D03*
X528799Y1976750D03*
X568999Y1987050D03*
X553499D03*
X588499Y1986550D03*
X511999Y1987550D03*
X531500Y1987500D03*
X603999Y54350D03*
Y35350D03*
X651799Y59650D03*
Y40650D03*
X674999Y59050D03*
X675499Y42050D03*
X674999Y20550D03*
X624499Y61550D03*
X624999Y44550D03*
X624499Y23050D03*
X608499Y6550D03*
X625999Y7050D03*
X645499D03*
X660999D03*
X604999Y75350D03*
X603999Y133750D03*
X652799Y80650D03*
X649899Y138350D03*
X674999Y140550D03*
X675499Y121050D03*
Y103550D03*
Y74550D03*
Y89050D03*
X624499Y143050D03*
X624999Y123550D03*
X623899Y202550D03*
X604999Y173750D03*
X603999Y152750D03*
X650899Y178350D03*
X649899Y157350D03*
X662499Y218050D03*
X642999D03*
X625499Y217550D03*
X605499D03*
X675999Y180550D03*
X674999Y159550D03*
X625499Y183050D03*
X624499Y162050D03*
X656499Y307050D03*
X653999Y286550D03*
X627999Y280050D03*
X627499Y299550D03*
X627999Y262550D03*
Y248050D03*
X599799Y385150D03*
X600299Y365650D03*
X599299Y344650D03*
X659899Y363250D03*
X632399Y358750D03*
X635399Y376250D03*
X607399Y380250D03*
X643599Y395950D03*
X655999Y344050D03*
X656499Y324550D03*
X628499Y339550D03*
X628200Y320000D03*
X644099Y450950D03*
X644599Y416950D03*
X644099Y436450D03*
X621499Y466550D03*
X621999Y432550D03*
X621499Y452050D03*
X620999Y411550D03*
X666999Y476550D03*
X643499Y546750D03*
X642499Y525750D03*
X613700Y504600D03*
X621499Y484050D03*
X593499Y499050D03*
X666499Y547050D03*
X666999Y508550D03*
X666499Y528050D03*
X666999Y491050D03*
X642999Y566250D03*
X640599Y604650D03*
X673999Y645150D03*
X645099Y639150D03*
X631999Y639650D03*
X665999Y623550D03*
X620499D03*
Y609050D03*
X595999Y641550D03*
Y624050D03*
Y609550D03*
X667499Y568050D03*
X651999Y718350D03*
X648999Y702350D03*
X629099Y714050D03*
X605299Y661750D03*
X609499Y708050D03*
X607499Y726550D03*
X647499Y689050D03*
Y671550D03*
Y657050D03*
X622999Y689550D03*
Y672050D03*
X597999Y690050D03*
X647399Y742150D03*
X653099Y803350D03*
X621499Y767150D03*
X633499Y750150D03*
X606999Y797050D03*
Y778050D03*
X607499Y758550D03*
Y741050D03*
X664999Y805050D03*
Y786050D03*
X665499Y766550D03*
X645799Y816650D03*
X642599Y883250D03*
X641599Y862250D03*
Y843250D03*
X621999Y835050D03*
X612999Y854550D03*
X629499Y853050D03*
Y868550D03*
X613499Y868050D03*
X663499Y896050D03*
X663999Y876550D03*
Y844550D03*
Y859050D03*
X665999Y826050D03*
X639499Y971150D03*
Y952150D03*
X616699Y967250D03*
Y948250D03*
X658999Y959050D03*
X656999Y977550D03*
X603499Y904050D03*
X601499Y954550D03*
Y922550D03*
Y937050D03*
X664499Y936050D03*
X663499Y915050D03*
X673999Y1036550D03*
Y1017550D03*
X674699Y1061450D03*
X611399Y1045650D03*
Y1026650D03*
X617699Y988250D03*
X656499Y1048050D03*
Y1029050D03*
X656999Y1009550D03*
Y992050D03*
X631999Y1001550D03*
X629999Y1052050D03*
Y1020050D03*
Y1034550D03*
X600999Y1002050D03*
X598999Y1052550D03*
Y1020550D03*
Y1035050D03*
X633999Y1103050D03*
X669499Y1116550D03*
X616499Y1115050D03*
X605999Y1102050D03*
X598999Y1114550D03*
X674699Y1080450D03*
X674999Y1134950D03*
X641799Y1137650D03*
X627699Y1143550D03*
X612399Y1066650D03*
X629499Y1090550D03*
Y1071550D03*
X598499Y1091050D03*
Y1072050D03*
X603899Y1157850D03*
X626199Y1183450D03*
X597599Y1196050D03*
X596599Y1215050D03*
X651599Y1203050D03*
X650599Y1182050D03*
X651299Y1174150D03*
X650299Y1153150D03*
X668199Y1173850D03*
X667199Y1152850D03*
X671199Y1213750D03*
X670199Y1192750D03*
X628699Y1164550D03*
X668699Y1227650D03*
X672999Y1303450D03*
X608899Y1305050D03*
X600899Y1238650D03*
X630499Y1243950D03*
X657099Y1272850D03*
X657799Y1288450D03*
X656399Y1307050D03*
X618199Y1296250D03*
Y1268250D03*
Y1287250D03*
X617599Y1246250D03*
Y1260750D03*
X638999Y1286550D03*
Y1295550D03*
Y1267550D03*
X598499Y1280550D03*
X598999Y1292550D03*
X598499Y1261550D03*
X671999Y1324950D03*
X631799Y1322650D03*
X605599Y1326350D03*
X665699Y1337250D03*
X606199Y1338250D03*
X617899Y1360850D03*
X625499Y1383450D03*
X632499Y1347950D03*
X599999Y1382550D03*
X599499Y1351550D03*
Y1370550D03*
X654999Y1385050D03*
X654499Y1373050D03*
Y1354050D03*
X659699Y1445950D03*
X604899Y1407750D03*
X601299Y1447650D03*
X636799Y1461250D03*
X626799Y1432350D03*
X627499Y1406050D03*
X665699Y1462250D03*
X652999Y1435550D03*
Y1418050D03*
Y1403550D03*
X656099Y1479550D03*
X625199Y1489150D03*
X610899Y1496750D03*
X672399Y1508750D03*
X673699Y1535350D03*
X662099Y1549650D03*
X643099Y1541350D03*
X599799Y1544650D03*
X617699Y1530350D03*
X670699Y1603150D03*
X671399Y1625350D03*
X628499Y1636650D03*
X633499Y1615450D03*
X635500Y1603900D03*
X652399Y1575850D03*
X623499Y1564050D03*
X652499Y1618550D03*
Y1609550D03*
X639200Y1576200D03*
X612499Y1615550D03*
X611900Y1577900D03*
X611999Y1603550D03*
X649399Y1644950D03*
X657099Y1668850D03*
X635099Y1691150D03*
X607599Y1716450D03*
X593399Y1668850D03*
X627299Y1659550D03*
X600599Y1645450D03*
X674999Y1676550D03*
X656499Y1697050D03*
X609499Y1692050D03*
Y1675050D03*
X642499Y1709050D03*
X665399Y1752350D03*
X650399Y1771250D03*
X593299Y1760950D03*
X619499Y1803150D03*
X627273Y1793905D03*
X606999Y1745550D03*
X625499Y1725050D03*
X675499Y1757050D03*
X675999Y1769050D03*
X675499Y1738050D03*
X642400Y1800100D03*
X659159Y1792278D03*
X626999Y1800050D03*
X645099Y1877550D03*
X667999Y1870950D03*
X632799Y1820450D03*
X627494Y1829068D03*
X608599Y1810750D03*
X669399Y1855350D03*
X627499Y1855950D03*
X611999D03*
X630699Y1872750D03*
X602799Y1887350D03*
X640999Y1815550D03*
X595199Y1820910D03*
X659549Y1815384D03*
X644049Y1810834D03*
X659549Y1810634D03*
X646799Y1926450D03*
X645399Y1906150D03*
X673899Y1966850D03*
Y1938850D03*
Y1957850D03*
X674899Y1920350D03*
Y1911350D03*
Y1892350D03*
X660299Y1964550D03*
Y1936550D03*
Y1955550D03*
X661299Y1918050D03*
Y1909050D03*
Y1890050D03*
X629699Y1947250D03*
Y1919250D03*
Y1938250D03*
X630699Y1900750D03*
Y1891750D03*
X601799Y1961850D03*
Y1933850D03*
Y1952850D03*
X602799Y1915350D03*
Y1906350D03*
X616499Y1913050D03*
Y1922050D03*
Y1894050D03*
X615499Y1959550D03*
Y1968550D03*
Y1940550D03*
X644999Y1953050D03*
X645499Y1965050D03*
X644999Y1934050D03*
X659299Y1976250D03*
X643799D03*
X622799D03*
X605299Y1975750D03*
X642499Y1987050D03*
X626999D03*
X661999Y1986550D03*
X605999Y1987050D03*
X751499Y48350D03*
X694999Y62650D03*
X757499Y63050D03*
Y44050D03*
X725499Y62050D03*
X725999Y45050D03*
X725499Y23550D03*
X680499Y6550D03*
X697999Y7050D03*
X712499Y6050D03*
X729999Y6550D03*
X749499D03*
X752099Y112150D03*
X738199Y137450D03*
X695999Y102650D03*
X694999Y81650D03*
X699699Y141750D03*
X758499Y84050D03*
X725499Y143550D03*
X725999Y124050D03*
Y106550D03*
Y77550D03*
Y92050D03*
X728899Y204550D03*
X688999Y196550D03*
X700699Y181750D03*
X699699Y160750D03*
X749499Y218550D03*
X729499D03*
X711999Y218050D03*
X677999D03*
X726499Y183550D03*
X725499Y162550D03*
X711999Y307550D03*
Y293050D03*
X723200Y275500D03*
X711499Y252550D03*
X680500Y280700D03*
X682999Y300050D03*
X683499Y263050D03*
Y248550D03*
X749899Y398550D03*
X711499Y344550D03*
X711999Y325050D03*
X683999Y340050D03*
X682999Y319050D03*
X713699Y455450D03*
X713199Y474950D03*
X712699Y434450D03*
X750399Y453550D03*
X750899Y419550D03*
X750399Y439050D03*
X694999Y480550D03*
X737999Y467050D03*
X691399Y548350D03*
X755699Y528650D03*
X756199Y509150D03*
X755199Y488150D03*
X754499Y564650D03*
X713099Y561550D03*
X713599Y542050D03*
X712599Y521050D03*
X713199Y489450D03*
X695499Y521050D03*
X695999Y501550D03*
X737999Y559050D03*
X738499Y539550D03*
Y522050D03*
Y507550D03*
X738999Y488050D03*
X691899Y588850D03*
X692399Y569350D03*
X754999Y605150D03*
X755499Y585650D03*
X717099Y636050D03*
X729699Y640350D03*
X731499Y604050D03*
Y586550D03*
Y572050D03*
X690499Y623050D03*
X720899Y712250D03*
X732499Y729250D03*
X681899Y713650D03*
X679299Y703050D03*
X727099Y715050D03*
X739399Y688150D03*
X747999Y670750D03*
X723499Y654850D03*
X693999Y648150D03*
X754999Y694050D03*
X702999Y688050D03*
Y670550D03*
Y656050D03*
X678499Y688550D03*
Y671050D03*
X749999Y700050D03*
X710899Y751150D03*
X696299Y741850D03*
X685999Y780050D03*
X694599Y763450D03*
X743099Y785350D03*
X733799Y761450D03*
X716599Y736850D03*
X723999Y802350D03*
Y783350D03*
X687099Y804650D03*
X706999Y811550D03*
Y792550D03*
X707499Y773050D03*
X757499Y745342D03*
X728499Y841850D03*
X724999Y823350D03*
X688099Y844650D03*
X687099Y823650D03*
X729999Y881850D03*
Y862850D03*
X751599Y887350D03*
X705999Y851050D03*
Y865550D03*
X707999Y832550D03*
X751499Y855550D03*
Y836550D03*
X751999Y817050D03*
X707399Y918550D03*
Y899550D03*
X678299Y978350D03*
X730999Y902850D03*
X688099Y936350D03*
X687099Y915350D03*
Y896350D03*
X724699Y976250D03*
X723699Y955250D03*
Y936250D03*
X752599Y927350D03*
X751599Y906350D03*
X706499Y942550D03*
X749999Y965550D03*
Y946550D03*
X751399Y1023550D03*
Y1004550D03*
X752399Y1052550D03*
X734999Y1030550D03*
Y1045050D03*
X713999Y1049050D03*
Y1031550D03*
Y1017050D03*
X678299Y997350D03*
X694999Y993050D03*
X692999Y1043550D03*
Y1011550D03*
Y1026050D03*
X750999Y986550D03*
X734999Y1062550D03*
X713499Y1068550D03*
X737999Y1119050D03*
X727499Y1106050D03*
X720499Y1118550D03*
X709999Y1105550D03*
X700499Y1118550D03*
X689999Y1105550D03*
X727499Y1132650D03*
X704299D03*
X692499Y1082050D03*
Y1063050D03*
X753999Y1100050D03*
X713599Y1214650D03*
X756799Y1217650D03*
X758799Y1190150D03*
Y1199150D03*
X717999Y1169150D03*
X716999Y1148150D03*
X714399Y1199750D03*
X713399Y1178750D03*
X735999Y1220550D03*
Y1206050D03*
X737999Y1187550D03*
Y1178550D03*
Y1159550D03*
X695999Y1217550D03*
Y1203050D03*
X697999Y1184550D03*
X697499Y1172550D03*
Y1153550D03*
X755600Y1149800D03*
X684299Y1249550D03*
X740799Y1298750D03*
X723499Y1292650D03*
Y1278150D03*
X725499Y1250650D03*
Y1259650D03*
Y1231650D03*
X755399Y1300650D03*
Y1286150D03*
X757399Y1258650D03*
Y1267650D03*
Y1239650D03*
X756799Y1232150D03*
X709699Y1264550D03*
X708699Y1243550D03*
X740499Y1252550D03*
Y1270050D03*
X695999Y1235050D03*
X758499Y1371050D03*
X739199Y1348950D03*
X742099Y1320650D03*
X719199Y1322350D03*
X695999Y1323350D03*
X677999Y1347550D03*
X680299Y1365850D03*
X713899Y1386450D03*
X707899Y1346250D03*
X734199Y1373850D03*
X694999Y1388050D03*
Y1379050D03*
Y1360050D03*
X702299Y1404450D03*
X736199Y1399050D03*
X741099Y1450250D03*
X737799Y1428350D03*
X716899Y1459850D03*
X700899Y1450250D03*
X681299Y1393150D03*
X678299Y1425050D03*
X686999Y1468850D03*
X719499Y1446650D03*
X721899Y1419050D03*
X754999Y1420050D03*
Y1437550D03*
X692999Y1421050D03*
Y1406550D03*
X741099Y1498150D03*
X729199Y1492750D03*
X716199Y1503050D03*
X735799Y1533650D03*
X714599Y1533950D03*
X708899Y1549250D03*
X685299Y1551950D03*
X747199Y1509150D03*
X755499Y1507550D03*
X754000Y1551000D03*
X734499Y1563550D03*
X722199Y1564250D03*
X706700Y1579900D03*
X698599Y1568550D03*
X681299Y1579150D03*
X693599Y1602450D03*
X686699Y1638650D03*
X742000Y1560000D03*
X743400Y1578700D03*
X719999Y1605050D03*
X751300Y1604900D03*
X732999Y1620050D03*
X756299Y1679050D03*
X738799Y1677250D03*
X750099Y1694950D03*
X756499Y1712150D03*
X739199Y1716750D03*
X721199Y1723750D03*
X727399Y1694350D03*
X717099Y1702450D03*
X693099Y1722350D03*
X691999Y1660550D03*
X751899Y1752150D03*
X747799Y1766750D03*
X729499Y1778750D03*
X729999Y1756450D03*
X747499Y1734350D03*
X702599Y1730550D03*
X709099Y1751850D03*
X690499Y1744950D03*
X694599Y1768450D03*
X690249Y1805634D03*
X715999Y1763050D03*
Y1772050D03*
Y1744050D03*
X693549Y1793134D03*
X706549Y1793634D03*
X744049Y1791634D03*
X740549Y1802634D03*
X753949Y1798194D03*
X705000Y1811900D03*
X755000Y1825000D03*
X686999Y1870250D03*
X728099Y1844750D03*
X747599Y1844250D03*
X743799Y1888850D03*
X728299D03*
X753699Y1879250D03*
X732199Y1878750D03*
X744699Y1868450D03*
X758399Y1868350D03*
X723199Y1867950D03*
X743399Y1855850D03*
X725899Y1855350D03*
X690899Y1855850D03*
X706399D03*
X697999Y1844550D03*
X732999Y1868550D03*
X711500Y1817700D03*
X704300Y1828400D03*
X686473Y1818375D03*
X740549Y1810384D03*
X696299Y1898850D03*
X716599Y1918450D03*
X728799Y1933050D03*
X709199Y1962950D03*
X698299Y1948050D03*
X676399Y1901150D03*
X695299Y1926450D03*
X711899Y1944050D03*
X736799Y1919450D03*
X728799Y1908150D03*
X705599Y1891850D03*
X730499Y1954650D03*
X755299Y1902150D03*
X739799D03*
X685499Y1959050D03*
Y1968050D03*
Y1940050D03*
X755500Y1914500D03*
X752500Y1954500D03*
X721499Y1974550D03*
X696299Y1976250D03*
X678799Y1975750D03*
X754999Y1987550D03*
X737499Y1987050D03*
X717999Y1987550D03*
X702499D03*
X679499Y1987050D03*
X774399Y54050D03*
X763399Y24150D03*
X817599Y43750D03*
X824899Y25150D03*
X813299Y68350D03*
Y49350D03*
X796999Y65550D03*
X797499Y48550D03*
X796999Y27050D03*
X764999Y6550D03*
X784499Y6050D03*
X801999Y6550D03*
X818999Y6050D03*
X836499Y6550D03*
X778399Y105250D03*
X775399Y80250D03*
X821199Y137450D03*
X813299Y110850D03*
X805899Y126150D03*
X767399Y140150D03*
X796599Y123450D03*
X814299Y89350D03*
X796999Y147050D03*
X797499Y127550D03*
Y110050D03*
Y81050D03*
Y95550D03*
X837499Y138550D03*
X838499Y145050D03*
X760799Y181950D03*
X779399Y200550D03*
X786499Y219050D03*
X800999Y216550D03*
X766999Y219050D03*
X797999Y187050D03*
X796999Y166050D03*
X821999Y193116D03*
X827499Y163550D03*
X820749Y163850D03*
X813249Y163800D03*
X839249Y164050D03*
X770999Y302050D03*
X785499Y291050D03*
X770999Y290050D03*
Y295550D03*
X827499Y313424D03*
X763571Y295622D03*
X777999Y296050D03*
X786978Y298529D03*
X836500Y274950D03*
X812500Y282750D03*
X839299Y390950D03*
X819299Y394250D03*
X838499Y352050D03*
X758778Y345000D03*
X768178Y333964D03*
X784499Y334050D03*
X840299Y430950D03*
X839299Y409950D03*
X820299Y434250D03*
X819299Y413250D03*
X802999Y466050D03*
X774999Y476550D03*
Y462050D03*
X825399Y540950D03*
X825899Y521450D03*
X824899Y500450D03*
X835599Y564050D03*
X834599Y543050D03*
X802999Y558050D03*
X803499Y538550D03*
Y521050D03*
Y506550D03*
X803999Y487050D03*
X775499Y553550D03*
X774499Y532550D03*
X774999Y494050D03*
X774499Y513550D03*
X835099Y583550D03*
X814499Y601550D03*
Y584050D03*
Y569550D03*
X789999Y602050D03*
Y584550D03*
Y570050D03*
X835150Y677650D03*
X764599Y655750D03*
X766499Y699050D03*
X782999Y699550D03*
X836149Y714050D03*
X766499Y705550D03*
X806500Y687250D03*
X778999Y806950D03*
X763099Y796350D03*
X835999Y799050D03*
Y781550D03*
Y767050D03*
X811499Y799550D03*
Y782050D03*
Y767550D03*
X837799Y754150D03*
X766499Y732842D03*
X762500Y734000D03*
X784939Y733550D03*
X825199Y850850D03*
X827699Y892450D03*
Y873450D03*
X776199Y879250D03*
X775199Y858250D03*
Y839250D03*
X800999Y892550D03*
X802999Y874050D03*
X801999Y853050D03*
Y834050D03*
X802499Y814550D03*
X828699Y913450D03*
X826999Y963150D03*
X773199Y960650D03*
X772199Y939650D03*
Y920650D03*
X800499Y944050D03*
Y963050D03*
X800999Y924550D03*
Y907050D03*
Y1037550D03*
Y1005550D03*
Y1020050D03*
X827999Y1003150D03*
X826999Y982150D03*
X777899Y1028050D03*
X776899Y1007050D03*
Y988050D03*
X801499Y984050D03*
X783999Y1096550D03*
X760999Y1095550D03*
X789499Y1099550D03*
X773499Y1101050D03*
X769499D03*
X773499Y1105050D03*
X769499D03*
X836149Y1118550D03*
X767083Y1134550D03*
X764549Y1138500D03*
X784439Y1136550D03*
X814000Y1087000D03*
X808299Y1175850D03*
X806599Y1189750D03*
X803599Y1211050D03*
X831499Y1209550D03*
Y1200550D03*
Y1181550D03*
X789499Y1225050D03*
X791499Y1206550D03*
X790999Y1194550D03*
Y1175550D03*
X839999Y1157550D03*
X826199Y1294450D03*
X828199Y1267850D03*
X788999Y1278150D03*
X791999Y1294450D03*
X808199Y1290350D03*
Y1275850D03*
X810199Y1248350D03*
Y1257350D03*
Y1229350D03*
X829499Y1242550D03*
Y1228050D03*
X789499Y1257050D03*
Y1239550D03*
X825500Y1379000D03*
X831499Y1324950D03*
X795299Y1326650D03*
X822199Y1335250D03*
X819199Y1353550D03*
X798299Y1344250D03*
X779399Y1361850D03*
X762499Y1335550D03*
Y1353050D03*
X799999Y1340550D03*
Y1358050D03*
X806499Y1390550D03*
X803299Y1426650D03*
X773999Y1393450D03*
X763399Y1401450D03*
X781999Y1434650D03*
X805899Y1464250D03*
X771399Y1474550D03*
X806499Y1408050D03*
X834499Y1397550D03*
X836600Y1416500D03*
X769300Y1488100D03*
X779000Y1488400D03*
X786500Y1488600D03*
X801300Y1489000D03*
X836625Y1487400D03*
X770999Y1500050D03*
X780499D03*
X839499Y1523550D03*
X773499Y1509050D03*
X769499D03*
X786999Y1506550D03*
X771225Y1539474D03*
X767936Y1540336D03*
X784577Y1535628D03*
X812550Y1494050D03*
X813300Y1604100D03*
X827199Y1622750D03*
X841499Y1638950D03*
X803599Y1618350D03*
X826499Y1609050D03*
X825999Y1578050D03*
X839899Y1562050D03*
X829200Y1719800D03*
X824100Y1719900D03*
X819400Y1721900D03*
X837199Y1660550D03*
X814599Y1642650D03*
X776999Y1647650D03*
X797299Y1646650D03*
X802899Y1670550D03*
X839199Y1683550D03*
X808899Y1698450D03*
X779999Y1717050D03*
X770399Y1699650D03*
X765099Y1664950D03*
X823499Y1693050D03*
Y1702050D03*
Y1674050D03*
X782999Y1687050D03*
X783499Y1699050D03*
X782999Y1668050D03*
X788000Y1788000D03*
X774500D03*
X812000Y1799500D03*
X819200Y1727100D03*
X808299Y1755250D03*
X794499Y1734550D03*
X770099Y1730350D03*
X779899Y1748150D03*
X787900Y1758800D03*
X765600Y1756800D03*
X821249Y1791250D03*
X811000Y1793000D03*
X827999Y1791550D03*
X829799Y1856350D03*
X809299D03*
X791799Y1855850D03*
X801099Y1844750D03*
X785599D03*
X765099D03*
X780799Y1888850D03*
X763299Y1888350D03*
X833100Y1878500D03*
X806199Y1879250D03*
X788699Y1878750D03*
X769199Y1879250D03*
X833199Y1868450D03*
X818900Y1870800D03*
X797199Y1868450D03*
X779699Y1867950D03*
X779399Y1855850D03*
X763899D03*
X770999Y1820550D03*
X822499Y1815164D03*
X791999Y1819050D03*
X783499Y1827050D03*
Y1907050D03*
X774499Y1908050D03*
X765999D03*
X838999Y1928550D03*
X790499Y1913050D03*
X775999Y1916050D03*
X840999Y1970550D03*
X767999Y1945173D03*
X764908Y1946592D03*
X768499Y1917550D03*
X785939Y1946800D03*
X812500Y1898500D03*
X813599Y1979950D03*
X789299Y1983850D03*
X829499Y1980250D03*
X829999Y1987550D03*
X812499Y1987050D03*
X792999Y1987550D03*
X777499D03*
X919800Y54600D03*
X844799Y19850D03*
X860799Y24150D03*
X885999Y21150D03*
X855999Y6550D03*
X871499D03*
X890999Y6050D03*
X908499Y6550D03*
X923999Y6050D03*
X924200Y69800D03*
X898800Y96000D03*
X890700Y132500D03*
X872100Y132700D03*
X854300Y132600D03*
X855500Y149500D03*
X873000Y148500D03*
X846500Y149500D03*
X891999Y146050D03*
X841499Y135550D03*
X861999Y146550D03*
X882499Y147050D03*
X896999Y141550D03*
X916499Y115050D03*
X906999Y224150D03*
X887400Y233555D03*
X871786Y233924D03*
Y218924D03*
Y203924D03*
X907999Y264150D03*
X906999Y243150D03*
X906399Y314250D03*
Y295250D03*
X847500Y246600D03*
X850999Y246550D03*
X874700Y244900D03*
X874900Y238600D03*
X871999Y283924D03*
X887400Y259700D03*
X879878Y247724D03*
X886200Y313924D03*
X886600Y303924D03*
X872136Y273924D03*
X858478Y274050D03*
X907399Y335250D03*
X875799Y386250D03*
X904999Y385050D03*
Y370550D03*
X854499Y387550D03*
Y373050D03*
X858400Y352300D03*
X847999Y352550D03*
X870600Y346700D03*
X876799Y426250D03*
X875799Y405250D03*
X884399Y462450D03*
Y443450D03*
X905499Y462050D03*
X904499Y441050D03*
Y422050D03*
X904999Y402550D03*
X854999Y464550D03*
X853999Y443550D03*
X854499Y405050D03*
X853999Y424550D03*
X861199Y546050D03*
X860199Y525050D03*
X885399Y483450D03*
X914699Y524650D03*
X913699Y503650D03*
Y484650D03*
X860699Y565550D03*
X898999Y622050D03*
Y604550D03*
X860499Y607550D03*
X861800Y591200D03*
X918999Y641550D03*
X875100Y644400D03*
X922049Y574375D03*
X870719Y609705D03*
X894000Y642400D03*
X870719Y639705D03*
X870773Y624705D03*
X895999Y720050D03*
Y702550D03*
X900999Y670050D03*
Y652550D03*
X918499Y712050D03*
X918999Y673550D03*
X918499Y693050D03*
X918999Y656050D03*
X875300Y650500D03*
X851300Y651700D03*
X847600Y651600D03*
X887401Y665000D03*
X881200Y652100D03*
X859999Y713050D03*
X871385Y719436D03*
X871786Y709482D03*
X871499Y689436D03*
X871786Y679436D03*
X860796Y678632D03*
X921399Y796350D03*
X921899Y776850D03*
Y759350D03*
Y744850D03*
X884499Y799050D03*
Y781550D03*
Y767050D03*
X859999Y799550D03*
Y782050D03*
Y767550D03*
X919499Y733050D03*
X856299Y753150D03*
X846799Y754150D03*
X865000Y752100D03*
X889699Y876050D03*
X847799Y828250D03*
X857099Y873450D03*
X920399Y886850D03*
Y869350D03*
Y854850D03*
X922399Y836350D03*
X921399Y815350D03*
X898499Y862050D03*
Y844550D03*
Y830050D03*
X873999Y862550D03*
Y845050D03*
Y830550D03*
X886999Y947250D03*
Y907350D03*
X867199Y941350D03*
X866199Y920350D03*
Y901350D03*
X850999Y962550D03*
Y943550D03*
X919899Y925350D03*
X920899Y946350D03*
X919899Y906350D03*
X922049Y978575D03*
X851999Y983550D03*
X921499Y1031050D03*
X920999Y1050550D03*
X921499Y1013550D03*
Y999050D03*
X847500Y1057800D03*
X851000Y1058000D03*
X874733Y1055792D03*
X874999Y1049550D03*
X870468Y1030227D03*
X880033Y1058592D03*
X886919Y1044478D03*
X870298Y1045227D03*
X870777Y1014948D03*
X921999Y1090550D03*
X920999Y1069550D03*
X887400Y1070600D03*
X859999Y1118550D03*
X841999D03*
X871499Y1124948D03*
X872086Y1114948D03*
X871999Y1094948D03*
X872086Y1084948D03*
X860133Y1084142D03*
X845799Y1190450D03*
X849799Y1199750D03*
X846499Y1170450D03*
X897299Y1182450D03*
X887999Y1209350D03*
X871399Y1201850D03*
Y1210850D03*
Y1182850D03*
X892499Y1224550D03*
X851999Y1218550D03*
X856400Y1157700D03*
X848999Y1158050D03*
X863300Y1153800D03*
X872099Y1268150D03*
X871399Y1291450D03*
X860099Y1295450D03*
X869399Y1243850D03*
Y1229350D03*
X890499Y1285550D03*
Y1271050D03*
X892499Y1252550D03*
Y1243550D03*
X850499Y1300050D03*
Y1282550D03*
Y1268050D03*
X852499Y1249550D03*
X851999Y1237550D03*
X875399Y1322650D03*
X868499Y1392550D03*
X890999Y1336550D03*
Y1354050D03*
X841999Y1341050D03*
Y1358550D03*
X860799Y1358925D03*
X894499Y1423550D03*
Y1441050D03*
X868499Y1410050D03*
X874100Y1461600D03*
X874900Y1454000D03*
X848861Y1462463D03*
X852500Y1462600D03*
X886913Y1449010D03*
X879727Y1463696D03*
X871836Y1450460D03*
Y1435460D03*
Y1420460D03*
X914599Y1521650D03*
X910899Y1549250D03*
X894499Y1522050D03*
Y1539550D03*
X895499Y1488050D03*
X902759Y1509585D03*
X861999Y1522550D03*
X843999Y1523550D03*
X858827Y1485696D03*
X887499Y1476050D03*
X872086Y1490460D03*
X871999Y1500460D03*
Y1520460D03*
X872086Y1530460D03*
X865300Y1557700D03*
X923599Y1634350D03*
X909700Y1576400D03*
X907500Y1604000D03*
X908899Y1630050D03*
X868099Y1635650D03*
X887299Y1620050D03*
X886900Y1604100D03*
X873099Y1572550D03*
X850099Y1572250D03*
X849900Y1605100D03*
X852499Y1621350D03*
X866499Y1603050D03*
Y1612050D03*
X864000Y1578200D03*
X858400Y1561900D03*
X850499Y1562050D03*
X914899Y1657550D03*
X922599Y1682150D03*
X903599Y1686850D03*
X895999Y1661250D03*
X877699Y1646650D03*
X855799Y1658250D03*
X882999Y1678250D03*
X864099Y1683550D03*
X842799Y1701150D03*
X902900Y1709800D03*
X900500Y1721500D03*
X842500Y1799000D03*
X879399Y1798150D03*
X911299Y1800850D03*
X866699Y1770950D03*
X853799Y1790850D03*
X844499Y1788050D03*
X921549Y1788475D03*
X863099Y1813150D03*
X903299Y1814750D03*
X894999Y1829050D03*
X922899Y1853650D03*
X905299Y1852650D03*
X900299Y1876950D03*
X842199Y1879250D03*
X851500Y1821400D03*
X849375Y1824982D03*
X854905Y1825583D03*
X914999Y1887050D03*
Y1868050D03*
X854480Y1867578D03*
X849999Y1867550D03*
X863700Y1867300D03*
X865300Y1858700D03*
X862499Y1823550D03*
X854977Y1818994D03*
X887401Y1881500D03*
X894000Y1868452D03*
X887499Y1855550D03*
X869999Y1855972D03*
X871836Y1840972D03*
X869634Y1826876D03*
X914899Y1912450D03*
X916599Y1942650D03*
X897599Y1938750D03*
X914899Y1972250D03*
X873399Y1963650D03*
X904299Y1954950D03*
X897299Y1904150D03*
X907599Y1930050D03*
X915499Y1899050D03*
X861414Y1928550D03*
X843999D03*
X856999Y1970050D03*
X849999Y1970550D03*
X865200Y1968000D03*
X859314Y1891365D03*
X871921Y1905972D03*
X871421Y1895972D03*
X872086Y1925972D03*
Y1935972D03*
X879399Y1974550D03*
X850499Y1977950D03*
X868699Y1983250D03*
X921499Y1986550D03*
X901999Y1987050D03*
X864999D03*
X849499D03*
X884499Y1986550D03*
X974699Y64650D03*
X977399Y44050D03*
X954799Y17850D03*
X974699Y21450D03*
X991399Y22450D03*
X1002699Y40050D03*
X991999Y56050D03*
X941499Y6550D03*
X960999D03*
X976499D03*
X995999Y6050D03*
X967499Y47050D03*
Y56050D03*
Y64050D03*
X961499Y100050D03*
X983099Y83650D03*
X1005299Y71350D03*
X977699Y109150D03*
X994399Y101250D03*
X981099Y123450D03*
X939199Y142050D03*
X968399Y137150D03*
X967999Y73050D03*
Y82050D03*
X946899Y122550D03*
X958999Y96050D03*
X988699Y174350D03*
X967399Y180350D03*
X956099Y181350D03*
X958799Y167350D03*
X1004799Y231450D03*
X1005299Y211950D03*
Y194450D03*
Y179950D03*
X952799Y231150D03*
Y213650D03*
Y199150D03*
X982999Y203550D03*
Y221050D03*
Y189050D03*
X932499Y223550D03*
Y206050D03*
Y191550D03*
X939549Y175175D03*
X1005299Y305450D03*
Y290950D03*
X1005799Y271450D03*
X1004799Y250450D03*
X952799Y310150D03*
X953299Y290650D03*
X952299Y269650D03*
Y250650D03*
X983999Y316050D03*
Y301550D03*
X933499Y304050D03*
X983499Y280550D03*
X982499Y259550D03*
Y240550D03*
X932999Y283050D03*
X931999Y262050D03*
Y243050D03*
X1005799Y382450D03*
X1004799Y361450D03*
X1005299Y322950D03*
X1004799Y342450D03*
X952299Y380650D03*
X952799Y342150D03*
X952299Y361650D03*
X952799Y324650D03*
X984499Y393050D03*
X983499Y372050D03*
Y353050D03*
X983999Y333550D03*
X933999Y395550D03*
X932999Y374550D03*
X933499Y336050D03*
X932999Y355550D03*
X933499Y318550D03*
X966199Y473350D03*
X1000699Y482350D03*
Y463350D03*
X954799Y451650D03*
Y434150D03*
Y419650D03*
X953299Y401650D03*
X983499Y464050D03*
X983999Y427050D03*
Y444550D03*
Y412550D03*
X933499Y447050D03*
X932999Y466550D03*
X933499Y429550D03*
Y415050D03*
X966499Y552050D03*
X967199Y513350D03*
X966199Y492350D03*
X1001699Y503350D03*
X1003499Y546350D03*
X1003999Y526850D03*
X951299Y560150D03*
Y541150D03*
X951799Y521650D03*
Y504150D03*
Y489650D03*
X985999Y536550D03*
Y554050D03*
Y522050D03*
X935499Y556550D03*
Y539050D03*
Y524550D03*
X984499Y504050D03*
X983499Y483050D03*
X933999Y506550D03*
X932999Y485550D03*
X967799Y606350D03*
X966799Y585350D03*
Y566350D03*
X1005999Y636350D03*
Y618850D03*
X1004499Y586350D03*
X1005999Y604350D03*
X1003499Y565350D03*
X950299Y631650D03*
Y614150D03*
Y599650D03*
X952299Y581150D03*
X969499Y639050D03*
X986499Y613550D03*
X985499Y592550D03*
Y573550D03*
X935999Y616050D03*
X934999Y595050D03*
Y576050D03*
X949799Y670150D03*
X950799Y691150D03*
X949799Y651150D03*
X969999Y730550D03*
X968999Y709550D03*
Y690550D03*
X969499Y653550D03*
Y671050D03*
Y795750D03*
X969999Y776250D03*
Y758750D03*
Y744250D03*
X994499Y803550D03*
Y784550D03*
X994999Y747550D03*
Y765050D03*
Y733050D03*
X943999Y806050D03*
X944499Y767550D03*
X943999Y787050D03*
X944499Y750050D03*
Y735550D03*
X970499Y879750D03*
Y862250D03*
Y847750D03*
Y835750D03*
X969499Y814750D03*
X992999Y894550D03*
X993499Y857550D03*
Y875050D03*
Y843050D03*
X942999Y877550D03*
Y860050D03*
Y845550D03*
X995499Y824550D03*
X944999Y827050D03*
X965999Y954550D03*
X994499Y973550D03*
Y956050D03*
Y941550D03*
X949299Y977450D03*
X970999Y939250D03*
X969999Y918250D03*
Y899250D03*
X993999Y934550D03*
X992999Y913550D03*
X943499Y937050D03*
X942499Y916050D03*
Y897050D03*
X994999Y1033050D03*
Y1045050D03*
X993999Y1012050D03*
Y993050D03*
X948799Y1047950D03*
Y1028950D03*
X949299Y1009450D03*
Y991950D03*
X971499Y1048050D03*
X971999Y1011050D03*
Y1028550D03*
Y996550D03*
X949799Y1068950D03*
Y1080950D03*
X998599Y1128450D03*
Y1110950D03*
Y1096450D03*
X950699Y1139750D03*
Y1122250D03*
Y1107750D03*
X975999Y1115550D03*
Y1133050D03*
Y1101050D03*
X925499Y1135550D03*
Y1118050D03*
Y1103550D03*
X972499Y1088050D03*
X971499Y1067050D03*
X999099Y1214450D03*
Y1199950D03*
Y1187950D03*
X998099Y1147950D03*
Y1166950D03*
X951199Y1225750D03*
Y1211250D03*
Y1199250D03*
X950199Y1159250D03*
Y1178250D03*
X976499Y1219050D03*
Y1204550D03*
X925999Y1221550D03*
Y1207050D03*
X976499Y1192550D03*
X975499Y1171550D03*
Y1152550D03*
X925999Y1195050D03*
X924999Y1174050D03*
Y1155050D03*
X999599Y1291450D03*
X998599Y1270450D03*
Y1251450D03*
X999099Y1231950D03*
X951699Y1302750D03*
X950699Y1281750D03*
Y1262750D03*
X951199Y1243250D03*
X976999Y1296050D03*
X975999Y1275050D03*
Y1256050D03*
X976499Y1236550D03*
X926499Y1298550D03*
X925499Y1277550D03*
X925999Y1239050D03*
X925499Y1258550D03*
X975100Y1342600D03*
X1000700Y1358100D03*
X996500Y1324800D03*
X952499Y1361850D03*
X944000Y1391900D03*
X943799Y1380850D03*
Y1342950D03*
X965099Y1324350D03*
X928499Y1325350D03*
X976499Y1377050D03*
Y1362550D03*
X925999Y1379550D03*
Y1365050D03*
X992500Y1397300D03*
X964400Y1409700D03*
X946700Y1426500D03*
X994200Y1421500D03*
X924999Y1471050D03*
X926499Y1456550D03*
X925499Y1435550D03*
X925999Y1397050D03*
X925499Y1416550D03*
X973200Y1516400D03*
X972500Y1529100D03*
X966600D03*
X961400Y1528700D03*
X961900Y1522400D03*
X967100Y1522800D03*
X973000D03*
X962100Y1516000D03*
X967300Y1516400D03*
X972700Y1534800D03*
X972000Y1547500D03*
X966100D03*
X960900Y1547100D03*
X961400Y1540800D03*
X966600Y1541200D03*
X972500D03*
X961600Y1534400D03*
X966800Y1534800D03*
X972700Y1553300D03*
X961600Y1552900D03*
X966800Y1553300D03*
X944000Y1511300D03*
X943199Y1531650D03*
X924499Y1541550D03*
X924999Y1503050D03*
X924499Y1522550D03*
X924999Y1485550D03*
X972000Y1566000D03*
X966100D03*
X960900Y1565600D03*
X961400Y1559300D03*
X966600Y1559700D03*
X972500D03*
X973000Y1572800D03*
X972300Y1585500D03*
X966400D03*
X961200Y1585100D03*
X961700Y1578800D03*
X966900Y1579200D03*
X972800D03*
X961900Y1572400D03*
X967100Y1572800D03*
X972400Y1592000D03*
X966500D03*
X961300Y1591600D03*
X972200Y1598400D03*
X966300D03*
X961100Y1598000D03*
X960600Y1604300D03*
X971700Y1604700D03*
X965800D03*
X944499Y1632650D03*
X925599Y1612050D03*
X933199Y1577550D03*
X925499Y1562550D03*
X990425Y1633898D03*
X987029Y1634075D03*
X981200Y1618002D03*
X989999Y1718050D03*
X958799Y1715750D03*
X957799Y1646950D03*
X955499Y1690850D03*
X941499Y1679550D03*
X940499Y1656950D03*
X931499Y1702050D03*
X989502Y1646000D03*
X988800Y1658300D03*
X989000Y1663802D03*
X987200Y1675600D03*
X989900Y1678800D03*
X941800Y1787700D03*
X934200Y1793500D03*
X993299Y1734350D03*
X994999Y1748950D03*
X976600Y1757100D03*
X965349Y1742000D03*
X949799Y1756250D03*
X976399Y1772250D03*
X954499Y1783550D03*
X941499Y1776250D03*
X932199Y1801850D03*
X971000Y1803000D03*
X999999Y1775250D03*
X976399Y1791150D03*
X993499Y1805550D03*
X928000Y1818500D03*
X1003599Y1846650D03*
X995699Y1858950D03*
X971500Y1871500D03*
X937199Y1869950D03*
X993499Y1824550D03*
Y1833550D03*
X987999Y1971950D03*
Y1949050D03*
X1000999Y1946350D03*
X991999Y1915750D03*
X966799Y1892150D03*
X974699Y1914450D03*
X945199Y1946350D03*
X955799Y1951950D03*
X954099Y1915450D03*
X938199Y1917150D03*
X1002500Y1953500D03*
X1001599Y1921450D03*
X992299Y1929050D03*
X989999Y1962650D03*
X980999Y1933350D03*
X947499Y1936050D03*
X946199Y1966650D03*
X937499Y1893850D03*
X971499Y1956050D03*
Y1965050D03*
Y1937050D03*
X930999Y1950050D03*
X931499Y1962050D03*
X930999Y1931050D03*
X955499Y1893050D03*
Y1902050D03*
X953799Y1977950D03*
X930199Y1979550D03*
X1005000Y1980500D03*
X973999Y1986550D03*
X956499Y1986050D03*
X936999Y1986550D03*
X1022000Y15500D03*
X1013499Y6550D03*
X1010599Y115550D03*
X1007299Y432450D03*
Y414950D03*
Y400450D03*
X1016499Y1301050D03*
X1023300Y1344400D03*
X1024300Y1365200D03*
X1022599Y1322950D03*
X1024300Y1393600D03*
X1008599Y1716050D03*
X1022299Y1715750D03*
X1008999Y1702450D03*
X1016899Y1731650D03*
X1026899Y1768550D03*
X1020299Y1746650D03*
X1015299Y1765950D03*
X1009999Y1797450D03*
X1011299Y1860650D03*
X1007599Y1818450D03*
G54D18*
X78150Y28858D03*
Y178464D03*
Y434370D03*
Y583976D03*
Y839882D03*
Y989488D03*
Y1245394D03*
Y1395000D03*
Y1650906D03*
Y1800512D03*
X158071Y191614D03*
Y341220D03*
Y597126D03*
Y746732D03*
Y1002638D03*
Y1152244D03*
Y1408150D03*
Y1557756D03*
Y1813662D03*
Y1963268D03*
X886417Y191614D03*
Y341220D03*
Y597126D03*
Y746732D03*
Y1002638D03*
Y1152244D03*
Y1408150D03*
Y1557756D03*
Y1813662D03*
Y1963268D03*
G54D10*
X-39052Y28742D03*
X-43327Y310478D03*
X-39686Y917251D03*
X-38801Y1082342D03*
X-44886Y1294251D03*
X-43103Y1928864D03*
X1071932Y32074D03*
X1074813Y1348051D03*
X1076613Y1740651D03*
X1074813Y1957551D03*
G54D17*
X68898Y17047D03*
Y190275D03*
Y422559D03*
Y595787D03*
Y828071D03*
Y1001299D03*
Y1233583D03*
Y1406811D03*
Y1639095D03*
Y1812323D03*
G54D12*
X9843Y153168D03*
Y265767D03*
Y353144D03*
Y717711D03*
Y762617D03*
Y875216D03*
Y1137420D03*
Y1250019D03*
Y1337396D03*
Y1701963D03*
Y1746869D03*
Y1859468D03*
G54D23*
X1019291Y1416024D03*
Y1694212D03*
G54D11*
X11999Y53550D03*
X11499Y34050D03*
X10000Y16500D03*
X11499Y142050D03*
X11999Y69050D03*
X11302Y161500D03*
X11500Y166000D03*
X9499Y301050D03*
Y281550D03*
X8999Y318550D03*
Y889550D03*
X8499Y979050D03*
X8999Y961550D03*
Y942050D03*
Y926550D03*
X8499Y907050D03*
X8999Y1060550D03*
Y1041050D03*
Y1025550D03*
X8499Y1006050D03*
X8999Y988550D03*
X8499Y1078050D03*
X6500Y1146000D03*
X13000Y1145500D03*
Y1151000D03*
X7000Y1151500D03*
X8799Y1302550D03*
X7499Y1282050D03*
X7999Y1264550D03*
X8299Y1320050D03*
X21500Y1122500D03*
Y1092500D03*
X17500D03*
X18000Y1145500D03*
X17500Y1150500D03*
X21299Y1300250D03*
X21799Y1282750D03*
X838999Y313550D03*
X821499Y314050D03*
X863999Y313550D03*
X879200Y1698700D03*
X879900Y1709300D03*
X883900Y1709500D03*
X855350Y1703201D03*
X875900Y1709500D03*
X892700Y1727800D03*
X864000Y1748000D03*
X892700Y1736500D03*
X994999Y1986550D03*
X1020499Y50550D03*
X1020999Y33050D03*
X1020499Y122550D03*
X1020999Y105050D03*
Y85550D03*
Y70050D03*
X1021499Y141050D03*
X1020999Y230550D03*
X1021499Y213050D03*
Y193550D03*
Y178050D03*
X1020999Y158550D03*
Y304550D03*
Y289050D03*
X1020499Y269550D03*
X1020999Y252050D03*
X1020499Y341550D03*
X1020999Y324050D03*
X1020499Y391550D03*
X1020999Y374050D03*
X1020499Y463550D03*
X1020999Y446050D03*
Y426550D03*
Y411050D03*
X1021999Y558550D03*
Y539050D03*
Y523550D03*
X1021499Y504050D03*
X1021999Y486550D03*
X1021499Y576050D03*
X1020999Y642550D03*
X1020499Y623050D03*
X1020999Y605550D03*
X1020499Y695050D03*
X1020999Y677550D03*
Y658050D03*
Y720050D03*
X1020499Y809550D03*
X1020999Y792050D03*
Y772550D03*
Y757050D03*
X1020499Y737550D03*
Y880550D03*
Y865050D03*
X1019999Y845550D03*
X1020499Y828050D03*
X1019999Y917550D03*
X1020499Y900050D03*
X1019999Y971050D03*
X1019499Y951550D03*
X1019999Y934050D03*
Y986550D03*
Y1058550D03*
Y1043050D03*
X1019499Y1023550D03*
X1019999Y1006050D03*
X1020499Y1134050D03*
Y1118550D03*
X1019999Y1099050D03*
X1020499Y1081550D03*
X1019499Y1198550D03*
Y1183050D03*
X1018999Y1163550D03*
X1019499Y1146050D03*
X1016999Y1219050D03*
X1016499Y1236550D03*
X1016999Y1256050D03*
Y1271550D03*
X1022499Y1802050D03*
X1022999Y1784550D03*
Y1821550D03*
Y1837050D03*
X1020499Y1877550D03*
X1020999Y1860050D03*
Y1912550D03*
Y1897050D03*
X1017499Y1954550D03*
X1017999Y1937050D03*
Y1987050D03*
X1023000Y1973000D03*
G54D21*
X144499Y1745550D03*
X137999Y1747723D03*
X129999Y1747050D03*
X123499D03*
X117499Y1745050D03*
G54D16*
X17720Y1903144D03*
X29532Y309561D03*
Y1029522D03*
X271657Y267711D03*
Y673223D03*
Y1078734D03*
Y1484246D03*
Y1889758D03*
X994098Y149601D03*
Y673223D03*
X994099Y1068892D03*
%LPC*%
G75*
G54D24*
G01X-71137Y-139897D02*
Y-219897D01*
G01D02*
X1129963D01*
G01X-75137Y-123897D02*
G02I-12000J0D01*
G01X-80287D02*
G02I-6850J0D01*
G01X-87137Y-139897D02*
Y-107897D01*
G01X-71137Y-123897D02*
X-103137D01*
G01X-71137Y-139897D02*
X1129963D01*
G01X-71137Y-175397D02*
X1129963D01*
G01X342463Y-139897D02*
Y-219897D01*
G01X479963Y-139897D02*
Y-219897D01*
G01X594963Y-139897D02*
Y-219897D01*
G01X762463Y-139897D02*
Y-219897D01*
G01X932463Y-139897D02*
Y-219897D01*
G01X1129963Y-139897D02*
Y-219897D01*
G01X1157963Y-123897D02*
G02I-12000J0D01*
G01X1152813D02*
G02I-6850J0D01*
G01X1145963Y-139897D02*
Y-107897D01*
G01X1161963Y-123897D02*
X1129963D01*
G54D25*
G01X-89222Y-207897D02*
Y-190397D01*
G01X-80052D02*
Y-207897D01*
G01Y-199147D02*
X-89222D01*
G01X-67137Y-207897D02*
X-68447Y-207605D01*
X-69757Y-206439D01*
X-70631Y-204397D01*
X-71067Y-202064D01*
X-70631Y-199730D01*
X-69757Y-197689D01*
X-68447Y-196522D01*
X-67137Y-196231D01*
X-65827Y-196522D01*
X-64517Y-197689D01*
X-63644Y-199730D01*
X-63425Y-202064D01*
X-63644Y-204397D01*
X-64517Y-206439D01*
X-65827Y-207605D01*
X-67137Y-207897D01*
G01X-53349D02*
Y-196231D01*
G01Y-199147D02*
X-52475Y-197689D01*
X-51165Y-196522D01*
X-49419Y-196231D01*
X-47891Y-196522D01*
X-46580Y-197689D01*
X-45925Y-199730D01*
Y-207897D01*
G01X-35412Y-200022D02*
X-28425D01*
X-29080Y-197980D01*
X-30172Y-196814D01*
X-31700Y-196231D01*
X-33229Y-196522D01*
X-34539Y-197397D01*
X-35412Y-199439D01*
X-35849Y-201189D01*
Y-202939D01*
X-35412Y-204689D01*
X-34320Y-206439D01*
X-33010Y-207605D01*
X-31482Y-207897D01*
X-29954Y-207314D01*
X-28425Y-205564D01*
G01X-19222Y-213147D02*
X-17912Y-213730D01*
X-16165Y-213147D01*
X-15074Y-211981D01*
X-14200Y-210522D01*
X-12891Y-205856D01*
X-10052Y-196231D01*
G01X-17039D02*
X-12891Y-205856D01*
G01X22109Y-198564D02*
X22983Y-197689D01*
X23638Y-196231D01*
X24075Y-194188D01*
X23638Y-192439D01*
X22765Y-191272D01*
X21236Y-190397D01*
X15341D01*
Y-207897D01*
X22546D01*
X24075Y-206731D01*
X24948Y-204980D01*
X25385Y-202939D01*
X24948Y-200897D01*
X23638Y-199147D01*
X22109Y-198564D01*
X15341D01*
G01X41793Y-207897D02*
Y-196231D01*
G01Y-198272D02*
X40920Y-197106D01*
X39609Y-196522D01*
X38081Y-196231D01*
X36553Y-196814D01*
X35243Y-197980D01*
X34369Y-199730D01*
X33933Y-202064D01*
X34369Y-204397D01*
X35243Y-206147D01*
X36553Y-207314D01*
X38081Y-207897D01*
X39609Y-207605D01*
X40920Y-206731D01*
X41793Y-205564D01*
G01X59293Y-190397D02*
Y-207897D01*
G01Y-205273D02*
X58420Y-206731D01*
X57109Y-207605D01*
X55581Y-207897D01*
X53835Y-207314D01*
X52525Y-205856D01*
X51651Y-204106D01*
X51433Y-202064D01*
X51651Y-200022D01*
X52525Y-198272D01*
X53835Y-196814D01*
X55581Y-196231D01*
X57109Y-196522D01*
X58201Y-197106D01*
X59293Y-198272D01*
G01X69806Y-212272D02*
X71335Y-213439D01*
X73081Y-213730D01*
X74609Y-213439D01*
X75920Y-211981D01*
X76793Y-209939D01*
Y-196231D01*
G01Y-198564D02*
X75920Y-197397D01*
X74609Y-196522D01*
X73081Y-196231D01*
X71335Y-196814D01*
X70243Y-197980D01*
X69369Y-200022D01*
X68933Y-202064D01*
X69151Y-203814D01*
X70025Y-205856D01*
X71335Y-207314D01*
X73081Y-207897D01*
X74391Y-207605D01*
X75920Y-206439D01*
X76793Y-205273D01*
G01X87088Y-200022D02*
X94075D01*
X93420Y-197980D01*
X92328Y-196814D01*
X90800Y-196231D01*
X89271Y-196522D01*
X87961Y-197397D01*
X87088Y-199439D01*
X86651Y-201189D01*
Y-202939D01*
X87088Y-204689D01*
X88180Y-206439D01*
X89490Y-207605D01*
X91018Y-207897D01*
X92546Y-207314D01*
X94075Y-205564D01*
G01X104806Y-207897D02*
Y-196231D01*
G01Y-198564D02*
X105898Y-197397D01*
X106990Y-196522D01*
X108518Y-196231D01*
X109609Y-196522D01*
X110920Y-197397D01*
G01X138060Y-207897D02*
Y-190397D01*
X142426D01*
X144173Y-191272D01*
X145483Y-192439D01*
X146575Y-194188D01*
X147448Y-196231D01*
X147666Y-199147D01*
X147448Y-202064D01*
X146575Y-204106D01*
X145483Y-205856D01*
X144173Y-207022D01*
X142426Y-207897D01*
X138060D01*
G01X155996D02*
Y-190397D01*
X161236D01*
X162983Y-191272D01*
X164293Y-193314D01*
X164730Y-195647D01*
X164293Y-197980D01*
X163201Y-199730D01*
X161236Y-200606D01*
X155996D01*
G01X179609Y-198564D02*
X180483Y-197689D01*
X181138Y-196231D01*
X181575Y-194188D01*
X181138Y-192439D01*
X180265Y-191272D01*
X178736Y-190397D01*
X172841D01*
Y-207897D01*
X180046D01*
X181575Y-206731D01*
X182448Y-204980D01*
X182885Y-202939D01*
X182448Y-200897D01*
X181138Y-199147D01*
X179609Y-198564D01*
X172841D01*
G01X208496Y-190397D02*
Y-207897D01*
X217230D01*
G01X230363D02*
X229053Y-207605D01*
X227743Y-206439D01*
X226869Y-204397D01*
X226433Y-202064D01*
X226869Y-199730D01*
X227743Y-197689D01*
X229053Y-196522D01*
X230363Y-196231D01*
X231673Y-196522D01*
X232983Y-197689D01*
X233856Y-199730D01*
X234075Y-202064D01*
X233856Y-204397D01*
X232983Y-206439D01*
X231673Y-207605D01*
X230363Y-207897D01*
G01X242404Y-196231D02*
X245025Y-207897D01*
X247863Y-196231D01*
X250701Y-207897D01*
X253322Y-196231D01*
G01X278496Y-190397D02*
Y-207897D01*
X287230D01*
G01X300363D02*
X299053Y-207605D01*
X297743Y-206439D01*
X296869Y-204397D01*
X296433Y-202064D01*
X296869Y-199730D01*
X297743Y-197689D01*
X299053Y-196522D01*
X300363Y-196231D01*
X301673Y-196522D01*
X302983Y-197689D01*
X303856Y-199730D01*
X304075Y-202064D01*
X303856Y-204397D01*
X302983Y-206439D01*
X301673Y-207605D01*
X300363Y-207897D01*
G01X314588Y-205856D02*
X315680Y-207022D01*
X317208Y-207897D01*
X318518D01*
X319828Y-207314D01*
X320701Y-206439D01*
X321138Y-205273D01*
X320920Y-203522D01*
X320046Y-202647D01*
X316116Y-200897D01*
X315243Y-198855D01*
X315680Y-197397D01*
X316553Y-196522D01*
X317863Y-196231D01*
X319173Y-196522D01*
X320483Y-197397D01*
G01X332088Y-205856D02*
X333180Y-207022D01*
X334708Y-207897D01*
X336018D01*
X337328Y-207314D01*
X338201Y-206439D01*
X338638Y-205273D01*
X338420Y-203522D01*
X337546Y-202647D01*
X333616Y-200897D01*
X332743Y-198855D01*
X333180Y-197397D01*
X334053Y-196522D01*
X335363Y-196231D01*
X336673Y-196522D01*
X337983Y-197397D01*
G01X94686Y-164897D02*
Y-147397D01*
X100363Y-161980D01*
X106040Y-147397D01*
Y-164897D01*
G01X117863D02*
X116553Y-164605D01*
X115243Y-163439D01*
X114369Y-161397D01*
X113933Y-159064D01*
X114369Y-156730D01*
X115243Y-154689D01*
X116553Y-153522D01*
X117863Y-153231D01*
X119173Y-153522D01*
X120483Y-154689D01*
X121356Y-156730D01*
X121575Y-159064D01*
X121356Y-161397D01*
X120483Y-163439D01*
X119173Y-164605D01*
X117863Y-164897D01*
G01X139293Y-147397D02*
Y-164897D01*
G01Y-162273D02*
X138420Y-163731D01*
X137109Y-164605D01*
X135581Y-164897D01*
X133835Y-164314D01*
X132525Y-162856D01*
X131651Y-161106D01*
X131433Y-159064D01*
X131651Y-157022D01*
X132525Y-155272D01*
X133835Y-153814D01*
X135581Y-153231D01*
X137109Y-153522D01*
X138201Y-154106D01*
X139293Y-155272D01*
G01X149588Y-157022D02*
X156575D01*
X155920Y-154980D01*
X154828Y-153814D01*
X153300Y-153231D01*
X151771Y-153522D01*
X150461Y-154397D01*
X149588Y-156439D01*
X149151Y-158189D01*
Y-159939D01*
X149588Y-161689D01*
X150680Y-163439D01*
X151990Y-164605D01*
X153518Y-164897D01*
X155046Y-164314D01*
X156575Y-162564D01*
G01X170363Y-164897D02*
Y-147397D01*
G01X376163Y-209897D02*
Y-192397D01*
X373543Y-195897D01*
G01Y-209897D02*
X378783D01*
G01X396283D02*
Y-192397D01*
X388204Y-204939D01*
X399122D01*
G01X406360Y-207273D02*
X407669Y-208731D01*
X409198Y-209605D01*
X411163Y-209897D01*
X413128Y-209314D01*
X414656Y-208147D01*
X415748Y-206106D01*
X415966Y-203772D01*
X415530Y-201439D01*
X414438Y-199980D01*
X412909Y-198814D01*
X411381Y-198522D01*
X409853Y-198814D01*
X407888Y-199980D01*
X408543Y-192397D01*
X414438D01*
G01X431283Y-209897D02*
Y-192397D01*
X423204Y-204939D01*
X434122D01*
G01X441360Y-207273D02*
X442669Y-208731D01*
X444198Y-209605D01*
X446163Y-209897D01*
X448128Y-209314D01*
X449656Y-208147D01*
X450748Y-206106D01*
X450966Y-203772D01*
X450530Y-201439D01*
X449438Y-199980D01*
X447909Y-198814D01*
X446381Y-198522D01*
X444853Y-198814D01*
X442888Y-199980D01*
X443543Y-192397D01*
X449438D01*
G01X363046Y-164897D02*
Y-147397D01*
X368286D01*
X370033Y-148272D01*
X371343Y-150314D01*
X371780Y-152647D01*
X371343Y-154980D01*
X370251Y-156730D01*
X368286Y-157606D01*
X363046D01*
G01X389716Y-148856D02*
X388406Y-147980D01*
X386878Y-147397D01*
X385131D01*
X383166Y-148272D01*
X381638Y-149730D01*
X380546Y-151481D01*
X379673Y-154397D01*
X379454Y-157022D01*
X379891Y-159647D01*
X380546Y-161397D01*
X381856Y-163147D01*
X383385Y-164314D01*
X384913Y-164897D01*
X386441D01*
X387970Y-164314D01*
X389280Y-163439D01*
X390372Y-162273D01*
G01X404159Y-155564D02*
X405033Y-154689D01*
X405688Y-153231D01*
X406125Y-151188D01*
X405688Y-149439D01*
X404815Y-148272D01*
X403286Y-147397D01*
X397391D01*
Y-164897D01*
X404596D01*
X406125Y-163731D01*
X406998Y-161980D01*
X407435Y-159939D01*
X406998Y-157897D01*
X405688Y-156147D01*
X404159Y-155564D01*
X397391D01*
G01X413363Y-170730D02*
X426463D01*
G01X432391Y-164897D02*
Y-147397D01*
X442435Y-164897D01*
Y-147397D01*
G01X454913Y-164897D02*
X453166Y-164605D01*
X451638Y-163439D01*
X450328Y-161689D01*
X449454Y-159647D01*
X449018Y-157314D01*
Y-154980D01*
X449454Y-152647D01*
X450328Y-150605D01*
X451638Y-148856D01*
X453166Y-147689D01*
X454913Y-147397D01*
X456659Y-147689D01*
X458188Y-148856D01*
X459498Y-150605D01*
X460372Y-152647D01*
X460808Y-154980D01*
Y-157314D01*
X460372Y-159647D01*
X459498Y-161689D01*
X458188Y-163439D01*
X456659Y-164605D01*
X454913Y-164897D01*
G01X505754Y-147397D02*
X511213Y-164897D01*
X516672Y-147397D01*
G01X533080Y-164897D02*
X524346D01*
Y-147397D01*
X533080D01*
G01X529586Y-155855D02*
X524346D01*
G01X541846Y-164897D02*
Y-147397D01*
X547305D01*
X549051Y-148272D01*
X550143Y-149439D01*
X550580Y-151772D01*
X550143Y-154106D01*
X548833Y-155564D01*
X547305Y-156439D01*
X541846D01*
G01X547305D02*
X550580Y-164897D01*
G01X563713Y-165480D02*
X563276Y-165189D01*
Y-164605D01*
X563713Y-164314D01*
X564150Y-164605D01*
Y-165189D01*
X563713Y-165480D01*
G01X524128Y-207564D02*
X525875Y-209022D01*
X527840Y-209897D01*
X529586D01*
X531333Y-209022D01*
X532643Y-207564D01*
X533298Y-205522D01*
X532861Y-203481D01*
X531770Y-201730D01*
X529805Y-200564D01*
X527185Y-199980D01*
X525656Y-198814D01*
X525001Y-196772D01*
X525438Y-194730D01*
X526530Y-193272D01*
X528058Y-192397D01*
X529586D01*
X531115Y-192980D01*
X532425Y-194439D01*
G01X540754Y-209897D02*
X546213Y-192397D01*
X551672Y-209897D01*
G01X549706Y-203772D02*
X542719D01*
G01X718030Y-192397D02*
Y-209897D01*
X709296D01*
G01X696600D02*
X696163Y-206106D01*
X695508Y-202897D01*
X694635Y-199980D01*
X693543Y-196772D01*
X691796Y-192397D01*
X700530D01*
G01X677353Y-201147D02*
X672986D01*
Y-206397D01*
X674296Y-208147D01*
X675825Y-209314D01*
X678008Y-209897D01*
X680191Y-209314D01*
X681720Y-208147D01*
X683030Y-206397D01*
X683903Y-204355D01*
X684340Y-202022D01*
Y-199980D01*
X683903Y-198231D01*
X683030Y-196188D01*
X681720Y-194439D01*
X680410Y-193272D01*
X678663Y-192397D01*
X677135D01*
X675388Y-192980D01*
X674078Y-194147D01*
G01X666185Y-209897D02*
Y-192397D01*
X656141Y-209897D01*
Y-192397D01*
G01X648466Y-209897D02*
Y-192397D01*
X644100D01*
X642353Y-193272D01*
X641043Y-194439D01*
X639951Y-196188D01*
X639078Y-198231D01*
X638860Y-201147D01*
X639078Y-204064D01*
X639951Y-206106D01*
X641043Y-207856D01*
X642353Y-209022D01*
X644100Y-209897D01*
X648466D01*
G01X630546Y-147397D02*
Y-164897D01*
X639280D01*
G01X656343D02*
Y-153231D01*
G01Y-155272D02*
X655470Y-154106D01*
X654159Y-153522D01*
X652631Y-153231D01*
X651103Y-153814D01*
X649793Y-154980D01*
X648919Y-156730D01*
X648483Y-159064D01*
X648919Y-161397D01*
X649793Y-163147D01*
X651103Y-164314D01*
X652631Y-164897D01*
X654159Y-164605D01*
X655470Y-163731D01*
X656343Y-162564D01*
G01X665328Y-170147D02*
X666638Y-170730D01*
X668385Y-170147D01*
X669476Y-168981D01*
X670350Y-167522D01*
X671659Y-162856D01*
X674498Y-153231D01*
G01X667511D02*
X671659Y-162856D01*
G01X684138Y-157022D02*
X691125D01*
X690470Y-154980D01*
X689378Y-153814D01*
X687850Y-153231D01*
X686321Y-153522D01*
X685011Y-154397D01*
X684138Y-156439D01*
X683701Y-158189D01*
Y-159939D01*
X684138Y-161689D01*
X685230Y-163439D01*
X686540Y-164605D01*
X688068Y-164897D01*
X689596Y-164314D01*
X691125Y-162564D01*
G01X701856Y-164897D02*
Y-153231D01*
G01Y-155564D02*
X702948Y-154397D01*
X704040Y-153522D01*
X705568Y-153231D01*
X706659Y-153522D01*
X707970Y-154397D01*
G01X719138Y-162856D02*
X720230Y-164022D01*
X721758Y-164897D01*
X723068D01*
X724378Y-164314D01*
X725251Y-163439D01*
X725688Y-162273D01*
X725470Y-160522D01*
X724596Y-159647D01*
X720666Y-157897D01*
X719793Y-155855D01*
X720230Y-154397D01*
X721103Y-153522D01*
X722413Y-153231D01*
X723723Y-153522D01*
X725033Y-154397D01*
G01X790596Y-209897D02*
Y-192397D01*
X796055D01*
X797801Y-193272D01*
X798893Y-194439D01*
X799330Y-196772D01*
X798893Y-199106D01*
X797583Y-200564D01*
X796055Y-201439D01*
X790596D01*
G01X796055D02*
X799330Y-209897D01*
G01X809188Y-202022D02*
X816175D01*
X815520Y-199980D01*
X814428Y-198814D01*
X812900Y-198231D01*
X811371Y-198522D01*
X810061Y-199397D01*
X809188Y-201439D01*
X808751Y-203189D01*
Y-204939D01*
X809188Y-206689D01*
X810280Y-208439D01*
X811590Y-209605D01*
X813118Y-209897D01*
X814646Y-209314D01*
X816175Y-207564D01*
G01X826033Y-209897D02*
Y-192397D01*
G01Y-201147D02*
X827125Y-199397D01*
X828435Y-198522D01*
X829745Y-198231D01*
X831709Y-198814D01*
X833020Y-199980D01*
X833893Y-202022D01*
Y-204355D01*
X833456Y-206689D01*
X832583Y-208439D01*
X831055Y-209605D01*
X829745Y-209897D01*
X828435Y-209605D01*
X827125Y-208731D01*
X826033Y-207273D01*
G01X844188Y-202022D02*
X851175D01*
X850520Y-199980D01*
X849428Y-198814D01*
X847900Y-198231D01*
X846371Y-198522D01*
X845061Y-199397D01*
X844188Y-201439D01*
X843751Y-203189D01*
Y-204939D01*
X844188Y-206689D01*
X845280Y-208439D01*
X846590Y-209605D01*
X848118Y-209897D01*
X849646Y-209314D01*
X851175Y-207564D01*
G01X868456Y-199689D02*
X866928Y-198522D01*
X865618Y-198231D01*
X863871Y-198814D01*
X862561Y-199980D01*
X861688Y-202022D01*
X861469Y-204064D01*
X861688Y-206106D01*
X862561Y-207856D01*
X863871Y-209314D01*
X865618Y-209897D01*
X867146Y-209314D01*
X868456Y-208147D01*
G01X885956Y-199689D02*
X884428Y-198522D01*
X883118Y-198231D01*
X881371Y-198814D01*
X880061Y-199980D01*
X879188Y-202022D01*
X878969Y-204064D01*
X879188Y-206106D01*
X880061Y-207856D01*
X881371Y-209314D01*
X883118Y-209897D01*
X884646Y-209314D01*
X885956Y-208147D01*
G01X903893Y-209897D02*
Y-198231D01*
G01Y-200272D02*
X903020Y-199106D01*
X901709Y-198522D01*
X900181Y-198231D01*
X898653Y-198814D01*
X897343Y-199980D01*
X896469Y-201730D01*
X896033Y-204064D01*
X896469Y-206397D01*
X897343Y-208147D01*
X898653Y-209314D01*
X900181Y-209897D01*
X901709Y-209605D01*
X903020Y-208731D01*
X903893Y-207564D01*
G01X781410Y-164897D02*
Y-147397D01*
X785776D01*
X787523Y-148272D01*
X788833Y-149439D01*
X789925Y-151188D01*
X790798Y-153231D01*
X791016Y-156147D01*
X790798Y-159064D01*
X789925Y-161106D01*
X788833Y-162856D01*
X787523Y-164022D01*
X785776Y-164897D01*
X781410D01*
G01X800438Y-157022D02*
X807425D01*
X806770Y-154980D01*
X805678Y-153814D01*
X804150Y-153231D01*
X802621Y-153522D01*
X801311Y-154397D01*
X800438Y-156439D01*
X800001Y-158189D01*
Y-159939D01*
X800438Y-161689D01*
X801530Y-163439D01*
X802840Y-164605D01*
X804368Y-164897D01*
X805896Y-164314D01*
X807425Y-162564D01*
G01X817938Y-162856D02*
X819030Y-164022D01*
X820558Y-164897D01*
X821868D01*
X823178Y-164314D01*
X824051Y-163439D01*
X824488Y-162273D01*
X824270Y-160522D01*
X823396Y-159647D01*
X819466Y-157897D01*
X818593Y-155855D01*
X819030Y-154397D01*
X819903Y-153522D01*
X821213Y-153231D01*
X822523Y-153522D01*
X823833Y-154397D01*
G01X838713Y-153231D02*
Y-164897D01*
G01Y-148564D02*
X838276Y-148272D01*
Y-147689D01*
X838713Y-147397D01*
X839150Y-147689D01*
Y-148272D01*
X838713Y-148564D01*
G01X853156Y-169272D02*
X854685Y-170439D01*
X856431Y-170730D01*
X857959Y-170439D01*
X859270Y-168981D01*
X860143Y-166939D01*
Y-153231D01*
G01Y-155564D02*
X859270Y-154397D01*
X857959Y-153522D01*
X856431Y-153231D01*
X854685Y-153814D01*
X853593Y-154980D01*
X852719Y-157022D01*
X852283Y-159064D01*
X852501Y-160814D01*
X853375Y-162856D01*
X854685Y-164314D01*
X856431Y-164897D01*
X857741Y-164605D01*
X859270Y-163439D01*
X860143Y-162273D01*
G01X870001Y-164897D02*
Y-153231D01*
G01Y-156147D02*
X870875Y-154689D01*
X872185Y-153522D01*
X873931Y-153231D01*
X875459Y-153522D01*
X876770Y-154689D01*
X877425Y-156730D01*
Y-164897D01*
G01X887938Y-157022D02*
X894925D01*
X894270Y-154980D01*
X893178Y-153814D01*
X891650Y-153231D01*
X890121Y-153522D01*
X888811Y-154397D01*
X887938Y-156439D01*
X887501Y-158189D01*
Y-159939D01*
X887938Y-161689D01*
X889030Y-163439D01*
X890340Y-164605D01*
X891868Y-164897D01*
X893396Y-164314D01*
X894925Y-162564D01*
G01X905656Y-164897D02*
Y-153231D01*
G01Y-155564D02*
X906748Y-154397D01*
X907840Y-153522D01*
X909368Y-153231D01*
X910459Y-153522D01*
X911770Y-154397D01*
G01X952413Y-192397D02*
X950666Y-192980D01*
X949356Y-194439D01*
X948483Y-196188D01*
X947828Y-198522D01*
X947610Y-201147D01*
X947828Y-203772D01*
X948483Y-206106D01*
X949356Y-207856D01*
X950666Y-209314D01*
X952413Y-209897D01*
X954159Y-209314D01*
X955470Y-207856D01*
X956343Y-206106D01*
X956998Y-203772D01*
X957216Y-201147D01*
X956998Y-198522D01*
X956343Y-196188D01*
X955470Y-194439D01*
X954159Y-192980D01*
X952413Y-192397D01*
G01X969913Y-209897D02*
X971441Y-209605D01*
X973188Y-208731D01*
X974280Y-207273D01*
X974716Y-205230D01*
X974280Y-203189D01*
X972970Y-201439D01*
X971005Y-200564D01*
X968821D01*
X967511Y-199980D01*
X966419Y-198522D01*
X965983Y-196481D01*
X966638Y-194439D01*
X968166Y-192980D01*
X969913Y-192397D01*
X971659Y-192980D01*
X973188Y-194439D01*
X973843Y-196481D01*
X973406Y-198522D01*
X972315Y-199980D01*
X971005Y-200564D01*
X968821D01*
X966856Y-201439D01*
X965546Y-203189D01*
X965110Y-205230D01*
X965546Y-207273D01*
X966638Y-208731D01*
X968385Y-209605D01*
X969913Y-209897D01*
G01X983483Y-210480D02*
X991343Y-192397D01*
G01X1004913D02*
X1003166Y-192980D01*
X1001856Y-194439D01*
X1000983Y-196188D01*
X1000328Y-198522D01*
X1000110Y-201147D01*
X1000328Y-203772D01*
X1000983Y-206106D01*
X1001856Y-207856D01*
X1003166Y-209314D01*
X1004913Y-209897D01*
X1006659Y-209314D01*
X1007970Y-207856D01*
X1008843Y-206106D01*
X1009498Y-203772D01*
X1009716Y-201147D01*
X1009498Y-198522D01*
X1008843Y-196188D01*
X1007970Y-194439D01*
X1006659Y-192980D01*
X1004913Y-192397D01*
G01X1022413Y-209897D02*
Y-192397D01*
X1019793Y-195897D01*
G01Y-209897D02*
X1025033D01*
G01X1035983Y-210480D02*
X1043843Y-192397D01*
G01X1053265Y-195314D02*
X1054575Y-193564D01*
X1056103Y-192689D01*
X1057850Y-192397D01*
X1060033Y-192980D01*
X1061561Y-194439D01*
X1061998Y-196188D01*
X1061780Y-197939D01*
X1060906Y-199397D01*
X1056540Y-202314D01*
X1054575Y-204355D01*
X1053265Y-207273D01*
X1052828Y-209897D01*
X1061998D01*
G01X1074913Y-192397D02*
X1073166Y-192980D01*
X1071856Y-194439D01*
X1070983Y-196188D01*
X1070328Y-198522D01*
X1070110Y-201147D01*
X1070328Y-203772D01*
X1070983Y-206106D01*
X1071856Y-207856D01*
X1073166Y-209314D01*
X1074913Y-209897D01*
X1076659Y-209314D01*
X1077970Y-207856D01*
X1078843Y-206106D01*
X1079498Y-203772D01*
X1079716Y-201147D01*
X1079498Y-198522D01*
X1078843Y-196188D01*
X1077970Y-194439D01*
X1076659Y-192980D01*
X1074913Y-192397D01*
G01X1092413Y-209897D02*
Y-192397D01*
X1089793Y-195897D01*
G01Y-209897D02*
X1095033D01*
G01X1112533D02*
Y-192397D01*
X1104454Y-204939D01*
X1115372D01*
G01X1000110Y-164897D02*
Y-147397D01*
X1004476D01*
X1006223Y-148272D01*
X1007533Y-149439D01*
X1008625Y-151188D01*
X1009498Y-153231D01*
X1009716Y-156147D01*
X1009498Y-159064D01*
X1008625Y-161106D01*
X1007533Y-162856D01*
X1006223Y-164022D01*
X1004476Y-164897D01*
X1000110D01*
G01X1026343D02*
Y-153231D01*
G01Y-155272D02*
X1025470Y-154106D01*
X1024159Y-153522D01*
X1022631Y-153231D01*
X1021103Y-153814D01*
X1019793Y-154980D01*
X1018919Y-156730D01*
X1018483Y-159064D01*
X1018919Y-161397D01*
X1019793Y-163147D01*
X1021103Y-164314D01*
X1022631Y-164897D01*
X1024159Y-164605D01*
X1025470Y-163731D01*
X1026343Y-162564D01*
G01X1039913Y-147397D02*
Y-164897D01*
G01X1036856Y-153231D02*
X1042970D01*
G01X1054138Y-157022D02*
X1061125D01*
X1060470Y-154980D01*
X1059378Y-153814D01*
X1057850Y-153231D01*
X1056321Y-153522D01*
X1055011Y-154397D01*
X1054138Y-156439D01*
X1053701Y-158189D01*
Y-159939D01*
X1054138Y-161689D01*
X1055230Y-163439D01*
X1056540Y-164605D01*
X1058068Y-164897D01*
X1059596Y-164314D01*
X1061125Y-162564D01*
M02*
